G04 ================== begin FILE IDENTIFICATION RECORD ==================*
G04 Layout Name:  DAT6MTH3AD0_t6m_cm_d_brd_103112_274.brd*
G04 Film Name:    panel*
G04 File Format:  Gerber RS274X*
G04 File Origin:  Cadence Allegro 16.3-S048*
G04 Origin Date:  Tue Nov 26 10:18:25 2013*
G04 *
G04 Layer:  MANUFACTURING/PHOTOPLOT_OUTLINE*
G04 Layer:  DRAWING FORMAT/TITLE_BLOCK*
G04 Layer:  DRAWING FORMAT/TITLE_DATA_PANEL*
G04 Layer:  BOARD GEOMETRY/ASSEMBLY_NOTES*
G04 *
G04 Offset:    (0.00 0.00)*
G04 Mirror:    No*
G04 Mode:      Positive*
G04 Rotation:  0*
G04 FullContactRelief:  No*
G04 UndefLineWidth:     6.00*
G04 ================== end FILE IDENTIFICATION RECORD ====================*
%FSLAX25Y25*MOIN*%
%IR0*IPPOS*OFA0.00000B0.00000*MIA0B0*SFA1.00000B1.00000*%
%ADD10C,.006*%
G75*
%LPD*%
G75*
G36*
G01X-50150Y774410D02*
G02I-1968J0D01*
G37*
G36*
G01D02*
G02I-1968J0D01*
G37*
G36*
G01D02*
G02I-1968J0D01*
G37*
G36*
G01D02*
G02I-1968J0D01*
G37*
G36*
G01D02*
G02I-1968J0D01*
G37*
G36*
G01D02*
G02I-1968J0D01*
G37*
G36*
G01X809055Y47244D02*
G02I-1968J0D01*
G37*
G36*
G01D02*
G02I-1968J0D01*
G37*
G36*
G01D02*
G02I-1968J0D01*
G37*
G36*
G01X953682Y138710D02*
G02I-1969J0D01*
G37*
G54D10*
G01X-79684Y822391D02*
X-187940Y825871D01*
G01X-178052Y825854D02*
X-178945Y827134D01*
X-179371Y828398D01*
X-179211Y833395D01*
X-178704Y834630D01*
X-177731Y835849D01*
G01X-170018Y827847D02*
X-170200Y827978D01*
X-170192Y828228D01*
X-170002Y828347D01*
X-169819Y828216D01*
X-169827Y827966D01*
X-170018Y827847D01*
G01X-162273Y835352D02*
X-163027Y835126D01*
X-163607Y834520D01*
X-164004Y833782D01*
X-164316Y832791D01*
X-164445Y831670D01*
X-164388Y830543D01*
X-164140Y829534D01*
X-163791Y828772D01*
X-163252Y828130D01*
X-162514Y827856D01*
X-161759Y828082D01*
X-161179Y828688D01*
X-160782Y829426D01*
X-160470Y830417D01*
X-160341Y831538D01*
X-160398Y832665D01*
X-160646Y833674D01*
X-160995Y834436D01*
X-161534Y835078D01*
X-162273Y835352D01*
G01X-155018Y827615D02*
X-154360Y827719D01*
X-153602Y828070D01*
X-153116Y828679D01*
X-152901Y829548D01*
X-153059Y830428D01*
X-153595Y831196D01*
X-154423Y831598D01*
X-155355Y831628D01*
X-155907Y831896D01*
X-156354Y832535D01*
X-156512Y833416D01*
X-156204Y834282D01*
X-155531Y834885D01*
X-154777Y835111D01*
X-154038Y834837D01*
X-153405Y834192D01*
X-153154Y833308D01*
X-153368Y832439D01*
X-153855Y831830D01*
X-154423Y831598D01*
X-155355Y831628D01*
X-156207Y831280D01*
X-156791Y830548D01*
X-157005Y829680D01*
X-156847Y828799D01*
X-156401Y828160D01*
X-155666Y827761D01*
X-155018Y827615D01*
G01X-147361Y832371D02*
X-147522Y827374D01*
G01X-147297Y834370D02*
X-147479Y834501D01*
X-147471Y834751D01*
X-147281Y834870D01*
X-147098Y834739D01*
X-147106Y834489D01*
X-147297Y834370D01*
G01X-141611Y827184D02*
X-141451Y832181D01*
G01X-141491Y830932D02*
X-141098Y831545D01*
X-140522Y832026D01*
X-139771Y832127D01*
X-139123Y831981D01*
X-138579Y831464D01*
X-138327Y830580D01*
X-138440Y827082D01*
G01X-130896Y831217D02*
X-131533Y831737D01*
X-132089Y831880D01*
X-132843Y831654D01*
X-133419Y831173D01*
X-133820Y830310D01*
X-133942Y829439D01*
X-133876Y828561D01*
X-133528Y827799D01*
X-132988Y827157D01*
X-132250Y826883D01*
X-131589Y827112D01*
X-131013Y827594D01*
G01X-126619Y826702D02*
X-126378Y834198D01*
G01X-126495Y830575D02*
X-126008Y831185D01*
X-125530Y831544D01*
X-124779Y831645D01*
X-124224Y831502D01*
X-123587Y830982D01*
X-123331Y830223D01*
X-123448Y826600D01*
G01X-117151Y823896D02*
X-116178Y825116D01*
X-115672Y826350D01*
X-115511Y831347D01*
X-115937Y832612D01*
X-116830Y833891D01*
G01X-176651Y838315D02*
X-176410Y845811D01*
X-174078Y845736D01*
X-173344Y845337D01*
X-172893Y844823D01*
X-172739Y843817D01*
X-172958Y842824D01*
X-173538Y842217D01*
X-174203Y841863D01*
X-176535Y841938D01*
G01X-174203Y841863D02*
X-172920Y838195D01*
G01X-168861Y844318D02*
X-168277Y845049D01*
X-167612Y845403D01*
X-166862Y845504D01*
X-165937Y845224D01*
X-165304Y844579D01*
X-165142Y843823D01*
X-165259Y843076D01*
X-165652Y842464D01*
X-167558Y841274D01*
X-168426Y840427D01*
X-169026Y839195D01*
X-169248Y838077D01*
X-165330Y837951D01*
G01X-162592Y837863D02*
X-162431Y842860D01*
G01X-162476Y841486D02*
X-162176Y842102D01*
X-161693Y842586D01*
X-161032Y842815D01*
X-160387Y842544D01*
X-159937Y842030D01*
X-159677Y841396D01*
X-159794Y837773D01*
G01X-159677Y841396D02*
X-159377Y842012D01*
X-158895Y842497D01*
X-158234Y842725D01*
X-157589Y842455D01*
X-157138Y841940D01*
X-156882Y841181D01*
X-156995Y837683D01*
G01X-155096Y837622D02*
X-154935Y842619D01*
G01X-154980Y841245D02*
X-154680Y841861D01*
X-154197Y842345D01*
X-153536Y842574D01*
X-152891Y842303D01*
X-152441Y841789D01*
X-152181Y841155D01*
X-152298Y837532D01*
G01X-152181Y841155D02*
X-151881Y841771D01*
X-151399Y842256D01*
X-150738Y842484D01*
X-150093Y842214D01*
X-149642Y841699D01*
X-149386Y840940D01*
X-149499Y837442D01*
G01X-95503Y820438D02*
X-79684Y822391D01*
X-95345Y825357D01*
X-95503Y820438D01*
G01X-71803Y9630D02*
Y43977D01*
G01X-63929Y821654D02*
G03X-71803Y813780I0J-7874D01*
G01Y7874D01*
G03X-63929Y0I7874J0D01*
G01X-7874D01*
Y631398D01*
X-7873D01*
Y672047D01*
G02X1Y679921I7874J0D01*
G01X28976D01*
G03X36850Y687795I0J7874D01*
G01Y813780D01*
G03X28976Y821654I-7874J0D01*
G01X-63929D01*
G01X-71803Y723091D02*
Y896939D01*
G01X385961Y893939D02*
X-71803D01*
G01X-66803Y894939D02*
X-71803Y893939D01*
X-66803Y892939D01*
Y894939D01*
G01X5906Y278740D02*
X25591D01*
G02X31496Y272835I0J-5905D01*
G01Y127165D01*
G02X25591Y121260I-5905J0D01*
G01X5906D01*
G03X0Y115354I0J-5906D01*
G01Y7874D01*
G03X7874Y0I7874J0D01*
G01X779528D01*
G03X787402Y7874I0J7874D01*
G01Y120669D01*
G03X781496Y126575I-5906J0D01*
G01X780315D01*
G02X774409Y132480I0J5906D01*
G01Y286024D01*
G02X780315Y291929I5906J-1D01*
G01X781496D01*
G03X787402Y297835I0J5906D01*
G01Y664173D01*
G03X779528Y672047I-7874J0D01*
G01X746693D01*
G02X738819Y679921I0J7874D01*
G01Y819708D01*
X738695Y819832D01*
X736866Y821652D01*
G01X-7874Y35030D02*
G02X0I3937J0D01*
G01X-7874Y54716D02*
G03X0I3937J0D01*
G01X5906Y278740D02*
G02X0Y284646I0J5906D01*
G01Y664173D01*
G02X7874Y672047I7874J0D01*
G01X40787D01*
G03X48661Y679921I0J7874D01*
G01Y819674D01*
X49201Y820214D01*
X50646Y821652D01*
G01X-7871Y302618D02*
X-7889D01*
G01X-7874Y325246D02*
G02X0I3937J0D01*
G01X-7874Y344932D02*
G03X0I3937J0D01*
G01X-7874Y485246D02*
G02X0I3937J0D01*
G01X-7874Y504932D02*
G03X0I3937J0D01*
G01X-7874Y635246D02*
G02X0I3937J0D01*
G01X-7874Y654932D02*
G03X0I3937J0D01*
G01X38493Y-241864D02*
Y-246864D01*
G01X37036Y-241864D02*
X39950D01*
G01X44860Y-246864D02*
X42326D01*
Y-241864D01*
X44860D01*
G01X43846Y-244281D02*
X42326D01*
G01X47426Y-241864D02*
Y-246864D01*
X49960D01*
G01X53793Y-247031D02*
X53666Y-246947D01*
Y-246781D01*
X53793Y-246697D01*
X53920Y-246781D01*
Y-246947D01*
X53793Y-247031D01*
G01Y-244781D02*
X53666Y-244697D01*
Y-244531D01*
X53793Y-244447D01*
X53920Y-244531D01*
Y-244697D01*
X53793Y-244781D01*
G01X58576Y-248531D02*
X57943Y-247697D01*
X57626Y-246864D01*
Y-243531D01*
X57943Y-242697D01*
X58576Y-241864D01*
G01X63993D02*
X63486Y-242031D01*
X63106Y-242447D01*
X62853Y-242947D01*
X62663Y-243614D01*
X62600Y-244364D01*
X62663Y-245114D01*
X62853Y-245781D01*
X63106Y-246281D01*
X63486Y-246697D01*
X63993Y-246864D01*
X64500Y-246697D01*
X64880Y-246281D01*
X65133Y-245781D01*
X65323Y-245114D01*
X65386Y-244364D01*
X65323Y-243614D01*
X65133Y-242947D01*
X64880Y-242447D01*
X64500Y-242031D01*
X63993Y-241864D01*
G01X67700Y-245864D02*
X68080Y-246447D01*
X68586Y-246781D01*
X69156Y-246864D01*
X69663Y-246781D01*
X70170Y-246364D01*
X70486Y-245864D01*
X70550Y-245364D01*
X70423Y-244781D01*
X69980Y-244364D01*
X69536Y-244197D01*
X68966D01*
G01X69536D02*
X69916Y-243947D01*
X70233Y-243531D01*
X70360Y-243031D01*
X70233Y-242531D01*
X69916Y-242114D01*
X69346Y-241864D01*
X68776Y-241947D01*
X68206Y-242281D01*
G01X74510Y-248531D02*
X75143Y-247697D01*
X75460Y-246864D01*
Y-243531D01*
X75143Y-242697D01*
X74510Y-241864D01*
G01X77900Y-245864D02*
X78280Y-246447D01*
X78786Y-246781D01*
X79356Y-246864D01*
X79863Y-246781D01*
X80370Y-246364D01*
X80686Y-245864D01*
X80750Y-245364D01*
X80623Y-244781D01*
X80180Y-244364D01*
X79736Y-244197D01*
X79166D01*
G01X79736D02*
X80116Y-243947D01*
X80433Y-243531D01*
X80560Y-243031D01*
X80433Y-242531D01*
X80116Y-242114D01*
X79546Y-241864D01*
X78976Y-241947D01*
X78406Y-242281D01*
G01X83190Y-242697D02*
X83570Y-242197D01*
X84013Y-241947D01*
X84520Y-241864D01*
X85153Y-242031D01*
X85596Y-242447D01*
X85723Y-242947D01*
X85660Y-243447D01*
X85406Y-243864D01*
X84140Y-244697D01*
X83570Y-245281D01*
X83190Y-246114D01*
X83063Y-246864D01*
X85723D01*
G01X89366D02*
X89493Y-245781D01*
X89683Y-244864D01*
X89936Y-244031D01*
X90253Y-243114D01*
X90760Y-241864D01*
X88226D01*
G01X93770Y-245197D02*
X95416D01*
G01X98490Y-242697D02*
X98870Y-242197D01*
X99313Y-241947D01*
X99820Y-241864D01*
X100453Y-242031D01*
X100896Y-242447D01*
X101023Y-242947D01*
X100960Y-243447D01*
X100706Y-243864D01*
X99440Y-244697D01*
X98870Y-245281D01*
X98490Y-246114D01*
X98363Y-246864D01*
X101023D01*
G01X103400Y-245864D02*
X103780Y-246447D01*
X104286Y-246781D01*
X104856Y-246864D01*
X105363Y-246781D01*
X105870Y-246364D01*
X106186Y-245864D01*
X106250Y-245364D01*
X106123Y-244781D01*
X105680Y-244364D01*
X105236Y-244197D01*
X104666D01*
G01X105236D02*
X105616Y-243947D01*
X105933Y-243531D01*
X106060Y-243031D01*
X105933Y-242531D01*
X105616Y-242114D01*
X105046Y-241864D01*
X104476Y-241947D01*
X103906Y-242281D01*
G01X110653Y-246864D02*
Y-241864D01*
X108310Y-245447D01*
X111476D01*
G01X113600Y-246114D02*
X113980Y-246531D01*
X114423Y-246781D01*
X114993Y-246864D01*
X115563Y-246697D01*
X116006Y-246364D01*
X116323Y-245781D01*
X116386Y-245114D01*
X116260Y-244447D01*
X115943Y-244031D01*
X115500Y-243697D01*
X115056Y-243614D01*
X114613Y-243697D01*
X114043Y-244031D01*
X114233Y-241864D01*
X115943D01*
G01X123990Y-246864D02*
Y-241864D01*
X126396D01*
G01X125510Y-244281D02*
X123990D01*
G01X128710Y-246864D02*
X130293Y-241864D01*
X131876Y-246864D01*
G01X131306Y-245114D02*
X129280D01*
G01X134063Y-246864D02*
X136723Y-241864D01*
G01X134063D02*
X136723Y-246864D01*
G01X140493Y-247031D02*
X140366Y-246947D01*
Y-246781D01*
X140493Y-246697D01*
X140620Y-246781D01*
Y-246947D01*
X140493Y-247031D01*
G01Y-244781D02*
X140366Y-244697D01*
Y-244531D01*
X140493Y-244447D01*
X140620Y-244531D01*
Y-244697D01*
X140493Y-244781D01*
G01X145276Y-248531D02*
X144643Y-247697D01*
X144326Y-246864D01*
Y-243531D01*
X144643Y-242697D01*
X145276Y-241864D01*
G01X150693D02*
X150186Y-242031D01*
X149806Y-242447D01*
X149553Y-242947D01*
X149363Y-243614D01*
X149300Y-244364D01*
X149363Y-245114D01*
X149553Y-245781D01*
X149806Y-246281D01*
X150186Y-246697D01*
X150693Y-246864D01*
X151200Y-246697D01*
X151580Y-246281D01*
X151833Y-245781D01*
X152023Y-245114D01*
X152086Y-244364D01*
X152023Y-243614D01*
X151833Y-242947D01*
X151580Y-242447D01*
X151200Y-242031D01*
X150693Y-241864D01*
G01X154400Y-245864D02*
X154780Y-246447D01*
X155286Y-246781D01*
X155856Y-246864D01*
X156363Y-246781D01*
X156870Y-246364D01*
X157186Y-245864D01*
X157250Y-245364D01*
X157123Y-244781D01*
X156680Y-244364D01*
X156236Y-244197D01*
X155666D01*
G01X156236D02*
X156616Y-243947D01*
X156933Y-243531D01*
X157060Y-243031D01*
X156933Y-242531D01*
X156616Y-242114D01*
X156046Y-241864D01*
X155476Y-241947D01*
X154906Y-242281D01*
G01X161210Y-248531D02*
X161843Y-247697D01*
X162160Y-246864D01*
Y-243531D01*
X161843Y-242697D01*
X161210Y-241864D01*
G01X164600Y-245864D02*
X164980Y-246447D01*
X165486Y-246781D01*
X166056Y-246864D01*
X166563Y-246781D01*
X167070Y-246364D01*
X167386Y-245864D01*
X167450Y-245364D01*
X167323Y-244781D01*
X166880Y-244364D01*
X166436Y-244197D01*
X165866D01*
G01X166436D02*
X166816Y-243947D01*
X167133Y-243531D01*
X167260Y-243031D01*
X167133Y-242531D01*
X166816Y-242114D01*
X166246Y-241864D01*
X165676Y-241947D01*
X165106Y-242281D01*
G01X170016Y-246281D02*
X170460Y-246697D01*
X170966Y-246864D01*
X171473Y-246697D01*
X171916Y-246197D01*
X172233Y-245447D01*
X172360Y-244697D01*
Y-243781D01*
X172233Y-243031D01*
X171916Y-242364D01*
X171536Y-242031D01*
X171093Y-241864D01*
X170586Y-242031D01*
X170206Y-242364D01*
X169953Y-242864D01*
X169826Y-243531D01*
X169953Y-244114D01*
X170270Y-244697D01*
X170650Y-245031D01*
X171093Y-245114D01*
X171600Y-244947D01*
X171980Y-244531D01*
X172360Y-243781D01*
G01X176066Y-246864D02*
X176193Y-245781D01*
X176383Y-244864D01*
X176636Y-244031D01*
X176953Y-243114D01*
X177460Y-241864D01*
X174926D01*
G01X180470Y-245197D02*
X182116D01*
G01X185000Y-245864D02*
X185380Y-246447D01*
X185886Y-246781D01*
X186456Y-246864D01*
X186963Y-246781D01*
X187470Y-246364D01*
X187786Y-245864D01*
X187850Y-245364D01*
X187723Y-244781D01*
X187280Y-244364D01*
X186836Y-244197D01*
X186266D01*
G01X186836D02*
X187216Y-243947D01*
X187533Y-243531D01*
X187660Y-243031D01*
X187533Y-242531D01*
X187216Y-242114D01*
X186646Y-241864D01*
X186076Y-241947D01*
X185506Y-242281D01*
G01X190290Y-244781D02*
X190733Y-244197D01*
X191113Y-243864D01*
X191620Y-243697D01*
X192063Y-243864D01*
X192380Y-244197D01*
X192633Y-244697D01*
X192696Y-245281D01*
X192633Y-245781D01*
X192380Y-246281D01*
X192000Y-246697D01*
X191556Y-246864D01*
X191050Y-246697D01*
X190606Y-246197D01*
X190353Y-245447D01*
X190290Y-244614D01*
X190416Y-243531D01*
X190606Y-242947D01*
X190923Y-242364D01*
X191366Y-241947D01*
X191810Y-241864D01*
X192253Y-242031D01*
X192570Y-242447D01*
G01X196593Y-246864D02*
Y-241864D01*
X195833Y-242864D01*
G01Y-246864D02*
X197353D01*
G01X202453D02*
Y-241864D01*
X200110Y-245447D01*
X203276D01*
G01X26493Y-176864D02*
Y-251864D01*
X526493D01*
Y-176864D01*
X26493D01*
G01X327026Y821652D02*
X50646D01*
G01X89851Y96614D02*
G03X107000I8574J-10787D01*
G01X89851Y710787D02*
G03X107000I8574J-10787D01*
G01X91339Y105512D02*
Y99696D01*
G01X89852Y96614D02*
G03X91339Y99696I-2450J3082D01*
G01X105512Y105512D02*
G03X91339I-7086J0D01*
G01Y719685D02*
Y713869D01*
G01X89852Y710787D02*
G03X91339Y713869I-2450J3082D01*
G01X105512Y719685D02*
G03X91339I-7086J0D01*
G01X105512Y99696D02*
Y105512D01*
G01Y99696D02*
G03X107000Y96614I3937J1D01*
G01X105512Y713869D02*
Y719685D01*
G01Y713869D02*
G03X107000Y710787I3937J1D01*
G01X221493Y-176864D02*
Y-251864D01*
G01Y-226864D02*
X324493D01*
Y-201864D01*
G01X221493D02*
X324493D01*
G01X332000Y-236864D02*
Y-231864D01*
X333266D01*
X333773Y-232114D01*
X334153Y-232447D01*
X334470Y-232947D01*
X334723Y-233531D01*
X334786Y-234364D01*
X334723Y-235197D01*
X334470Y-235781D01*
X334153Y-236281D01*
X333773Y-236614D01*
X333266Y-236864D01*
X332000D01*
G01X336910D02*
X338493Y-231864D01*
X340076Y-236864D01*
G01X339506Y-235114D02*
X337480D01*
G01X343593Y-231864D02*
Y-236864D01*
G01X342136Y-231864D02*
X345050D01*
G01X349960Y-236864D02*
X347426D01*
Y-231864D01*
X349960D01*
G01X348946Y-234281D02*
X347426D01*
G01X353793Y-237031D02*
X353666Y-236947D01*
Y-236781D01*
X353793Y-236697D01*
X353920Y-236781D01*
Y-236947D01*
X353793Y-237031D01*
G01Y-234781D02*
X353666Y-234697D01*
Y-234531D01*
X353793Y-234447D01*
X353920Y-234531D01*
Y-234697D01*
X353793Y-234781D01*
G01X326493Y-176864D02*
Y-251864D01*
G01X324493Y-176864D02*
Y-251864D01*
G01X326493Y-226864D02*
X526493D01*
G01X332126Y-211864D02*
Y-206864D01*
X333646D01*
X334153Y-207114D01*
X334533Y-207697D01*
X334660Y-208364D01*
X334533Y-209031D01*
X334216Y-209531D01*
X333646Y-209781D01*
X332126D01*
G01X337353Y-212031D02*
X339633Y-206864D01*
G01X342136Y-211864D02*
Y-206864D01*
X345050Y-211864D01*
Y-206864D01*
G01X348693Y-212031D02*
X348566Y-211947D01*
Y-211781D01*
X348693Y-211697D01*
X348820Y-211781D01*
Y-211947D01*
X348693Y-212031D01*
G01Y-209781D02*
X348566Y-209697D01*
Y-209531D01*
X348693Y-209447D01*
X348820Y-209531D01*
Y-209697D01*
X348693Y-209781D01*
G01X326493Y-201864D02*
X526493D01*
G01X332126Y-186864D02*
Y-181864D01*
X333646D01*
X334153Y-182114D01*
X334533Y-182697D01*
X334660Y-183364D01*
X334533Y-184031D01*
X334216Y-184531D01*
X333646Y-184781D01*
X332126D01*
G01X337226Y-186864D02*
Y-181864D01*
X338810D01*
X339316Y-182114D01*
X339633Y-182447D01*
X339760Y-183114D01*
X339633Y-183781D01*
X339253Y-184197D01*
X338810Y-184447D01*
X337226D01*
G01X338810D02*
X339760Y-186864D01*
G01X343593D02*
X343086Y-186781D01*
X342643Y-186447D01*
X342263Y-185947D01*
X342010Y-185364D01*
X341883Y-184697D01*
Y-184031D01*
X342010Y-183364D01*
X342263Y-182781D01*
X342643Y-182281D01*
X343086Y-181947D01*
X343593Y-181864D01*
X344100Y-181947D01*
X344543Y-182281D01*
X344923Y-182781D01*
X345176Y-183364D01*
X345303Y-184031D01*
Y-184697D01*
X345176Y-185364D01*
X344923Y-185947D01*
X344543Y-186447D01*
X344100Y-186781D01*
X343593Y-186864D01*
G01X347426Y-185864D02*
X347743Y-186364D01*
X348123Y-186697D01*
X348566Y-186864D01*
X349073Y-186697D01*
X349453Y-186364D01*
X349833Y-185864D01*
X349960Y-185197D01*
Y-181864D01*
G01X355060Y-186864D02*
X352526D01*
Y-181864D01*
X355060D01*
G01X354046Y-184281D02*
X352526D01*
G01X360286Y-182281D02*
X359906Y-182031D01*
X359463Y-181864D01*
X358956D01*
X358386Y-182114D01*
X357943Y-182531D01*
X357626Y-183031D01*
X357373Y-183864D01*
X357310Y-184614D01*
X357436Y-185364D01*
X357626Y-185864D01*
X358006Y-186364D01*
X358450Y-186697D01*
X358893Y-186864D01*
X359336D01*
X359780Y-186697D01*
X360160Y-186447D01*
X360476Y-186114D01*
G01X363993Y-181864D02*
Y-186864D01*
G01X362536Y-181864D02*
X365450D01*
G01X369093Y-187031D02*
X368966Y-186947D01*
Y-186781D01*
X369093Y-186697D01*
X369220Y-186781D01*
Y-186947D01*
X369093Y-187031D01*
G01Y-184781D02*
X368966Y-184697D01*
Y-184531D01*
X369093Y-184447D01*
X369220Y-184531D01*
Y-184697D01*
X369093Y-184781D01*
G01X327026Y821652D02*
X328915Y819773D01*
X328976Y819712D01*
Y792323D01*
G03X336457I3740J0D01*
G01Y819673D01*
X336476Y819692D01*
X338446Y821652D01*
G01X378606D02*
X338446D01*
G01X378606D02*
X380551Y819707D01*
Y741142D01*
G03X406929I13189J0D01*
G01Y819675D01*
X406946Y819692D01*
X408916Y821652D01*
G01X685296D02*
X408916D01*
G01X447126Y-236864D02*
Y-231864D01*
X448710D01*
X449216Y-232114D01*
X449533Y-232447D01*
X449660Y-233114D01*
X449533Y-233781D01*
X449153Y-234197D01*
X448710Y-234447D01*
X447126D01*
G01X448710D02*
X449660Y-236864D01*
G01X454760D02*
X452226D01*
Y-231864D01*
X454760D01*
G01X453746Y-234281D02*
X452226D01*
G01X457010Y-231864D02*
X458593Y-236864D01*
X460176Y-231864D01*
G01X463693Y-237031D02*
X463566Y-236947D01*
Y-236781D01*
X463693Y-236697D01*
X463820Y-236781D01*
Y-236947D01*
X463693Y-237031D01*
G01Y-234781D02*
X463566Y-234697D01*
Y-234531D01*
X463693Y-234447D01*
X463820Y-234531D01*
Y-234697D01*
X463693Y-234781D01*
G01X441493Y-226864D02*
Y-251864D01*
G01X438511Y893939D02*
X826772D01*
G01X490493Y-226864D02*
Y-251864D01*
G01X680097Y96167D02*
G03X697856I8880J-10537D01*
G01X681497Y105315D02*
Y99177D01*
G01X696457Y105315D02*
G03X681497I-7480J0D01*
G01X680097Y96166D02*
G03X681497Y99177I-2537J3011D01*
G01X680097Y710340D02*
G03X697856I8880J-10537D01*
G01X681497Y719488D02*
Y713350D01*
G01X680097Y710340D02*
G03X681497Y713350I-2537J3011D01*
G01X696457Y719488D02*
G03X681497I-7480J0D01*
G01X696457Y99177D02*
Y105315D01*
G01Y99177D02*
G03X697857Y96166I3937J0D01*
G01X696457Y713350D02*
Y719488D01*
G01Y713350D02*
G03X697857Y710340I3937J1D01*
G01X696716Y821652D02*
X694746Y819692D01*
X694724Y819670D01*
Y792323D01*
G02X687244I-3740J0D01*
G01Y819710D01*
X686388Y820566D01*
X685296Y821652D01*
G01X736866D02*
X696716D01*
G01X795276Y61000D02*
Y672047D01*
G03X787402Y679921I-7874J0D01*
G01X758504D01*
G02X750630Y687795I0J7874D01*
G01Y813780D01*
G02X758504Y821654I7874J0D01*
G01X818898D01*
G02X826772Y813780I0J-7874D01*
G01Y770654D01*
G01X795276Y29528D02*
G03X787402I-3937J0D01*
G01X795276D02*
G03X787402I-3937J0D01*
G01X795276Y49213D02*
G02X787402I-3937J0D01*
G01X795276D02*
G02X787402I-3937J0D01*
G01X795276Y329528D02*
G03X787402I-3937J0D01*
G01X795276D02*
G03X787402I-3937J0D01*
G01X795276Y349213D02*
G02X787402I-3937J0D01*
G01X795276D02*
G02X787402I-3937J0D01*
G01X795276Y479528D02*
G03X787402I-3937J0D01*
G01X795276D02*
G03X787402I-3937J0D01*
G01X795276Y499213D02*
G02X787402I-3937J0D01*
G01X795276D02*
G02X787402I-3937J0D01*
G01X795276Y629528D02*
G03X787402I-3937J0D01*
G01X795276D02*
G03X787402I-3937J0D01*
G01X795276Y649213D02*
G02X787402I-3937J0D01*
G01X795276D02*
G02X787402I-3937J0D01*
G01X818898Y0D02*
X795276D01*
Y61000D01*
G01X806725Y0D02*
X888985D01*
G01X806725Y821654D02*
X888985D01*
G01X826772Y61000D02*
Y7874D01*
G02X818898Y0I-7874J0D01*
G01X821772Y892939D02*
X826772Y893939D01*
X821772Y894939D01*
Y892939D01*
G01X826772Y770654D02*
Y61000D01*
G01X825404Y270514D02*
Y270492D01*
G01X826772Y723091D02*
Y896939D01*
G01X885985Y339036D02*
Y0D01*
G01X884985Y5000D02*
X885985Y0D01*
X886985Y5000D01*
X884985D01*
G01X885985Y391586D02*
Y821654D01*
G01X886985Y816654D02*
X885985Y821654D01*
X884985Y816654D01*
X886985D01*
G01X924435Y100038D02*
X924688Y100288D01*
X924878Y100704D01*
X925005Y101288D01*
X924878Y101788D01*
X924625Y102121D01*
X924181Y102371D01*
X922471D01*
Y97371D01*
X924561D01*
X925005Y97704D01*
X925258Y98204D01*
X925385Y98788D01*
X925258Y99371D01*
X924878Y99871D01*
X924435Y100038D01*
X922471D01*
G01X928141Y97371D02*
Y100704D01*
G01Y100038D02*
X928458Y100371D01*
X928775Y100621D01*
X929218Y100704D01*
X929535Y100621D01*
X929915Y100371D01*
G01X933178Y99621D02*
X935205D01*
X935015Y100204D01*
X934698Y100538D01*
X934255Y100704D01*
X933811Y100621D01*
X933431Y100371D01*
X933178Y99788D01*
X933051Y99288D01*
Y98788D01*
X933178Y98288D01*
X933495Y97788D01*
X933875Y97454D01*
X934318Y97371D01*
X934761Y97538D01*
X935205Y98038D01*
G01X940368Y97371D02*
Y100704D01*
G01Y100121D02*
X940115Y100454D01*
X939735Y100621D01*
X939291Y100704D01*
X938848Y100538D01*
X938468Y100204D01*
X938215Y99704D01*
X938088Y99038D01*
X938215Y98371D01*
X938468Y97871D01*
X938848Y97538D01*
X939291Y97371D01*
X939735Y97454D01*
X940115Y97704D01*
X940368Y98038D01*
G01X943251Y97371D02*
Y102371D01*
G01X945278Y100704D02*
X943251Y98788D01*
G01X944075Y99538D02*
X945405Y97371D01*
G01X949428Y102371D02*
Y97371D01*
G01X948541Y100704D02*
X950315D01*
G01X955668Y97371D02*
Y100704D01*
G01Y100121D02*
X955415Y100454D01*
X955035Y100621D01*
X954591Y100704D01*
X954148Y100538D01*
X953768Y100204D01*
X953515Y99704D01*
X953388Y99038D01*
X953515Y98371D01*
X953768Y97871D01*
X954148Y97538D01*
X954591Y97371D01*
X955035Y97454D01*
X955415Y97704D01*
X955668Y98038D01*
G01X958488Y97371D02*
Y102371D01*
G01Y99871D02*
X958805Y100371D01*
X959185Y100621D01*
X959565Y100704D01*
X960135Y100538D01*
X960515Y100204D01*
X960768Y99621D01*
Y98954D01*
X960641Y98288D01*
X960388Y97788D01*
X959945Y97454D01*
X959565Y97371D01*
X959185Y97454D01*
X958805Y97704D01*
X958488Y98121D01*
G01X964728Y97204D02*
X964601Y97288D01*
Y97454D01*
X964728Y97538D01*
X964855Y97454D01*
Y97288D01*
X964728Y97204D01*
G01Y99454D02*
X964601Y99538D01*
Y99704D01*
X964728Y99788D01*
X964855Y99704D01*
Y99538D01*
X964728Y99454D01*
G01X999225Y163902D02*
Y168902D01*
X1001631D01*
G01X1000745Y166485D02*
X999225D01*
G01X1005528Y163902D02*
X1005148Y163985D01*
X1004768Y164319D01*
X1004515Y164902D01*
X1004388Y165569D01*
X1004515Y166235D01*
X1004768Y166819D01*
X1005148Y167152D01*
X1005528Y167235D01*
X1005908Y167152D01*
X1006288Y166819D01*
X1006541Y166235D01*
X1006605Y165569D01*
X1006541Y164902D01*
X1006288Y164319D01*
X1005908Y163985D01*
X1005528Y163902D01*
G01X1009741D02*
Y167235D01*
G01Y166569D02*
X1010058Y166902D01*
X1010375Y167152D01*
X1010818Y167235D01*
X1011135Y167152D01*
X1011515Y166902D01*
G01X1019561Y163902D02*
Y168902D01*
X1021081D01*
X1021588Y168652D01*
X1021968Y168069D01*
X1022095Y167402D01*
X1021968Y166735D01*
X1021651Y166235D01*
X1021081Y165985D01*
X1019561D01*
G01X1027068Y163902D02*
Y167235D01*
G01Y166652D02*
X1026815Y166985D01*
X1026435Y167152D01*
X1025991Y167235D01*
X1025548Y167069D01*
X1025168Y166735D01*
X1024915Y166235D01*
X1024788Y165569D01*
X1024915Y164902D01*
X1025168Y164402D01*
X1025548Y164069D01*
X1025991Y163902D01*
X1026435Y163985D01*
X1026815Y164235D01*
X1027068Y164569D01*
G01X1029951Y163902D02*
Y167235D01*
G01Y166402D02*
X1030205Y166819D01*
X1030585Y167152D01*
X1031091Y167235D01*
X1031535Y167152D01*
X1031915Y166819D01*
X1032105Y166235D01*
Y163902D01*
G01X1035178Y166152D02*
X1037205D01*
X1037015Y166735D01*
X1036698Y167069D01*
X1036255Y167235D01*
X1035811Y167152D01*
X1035431Y166902D01*
X1035178Y166319D01*
X1035051Y165819D01*
Y165319D01*
X1035178Y164819D01*
X1035495Y164319D01*
X1035875Y163985D01*
X1036318Y163902D01*
X1036761Y164069D01*
X1037205Y164569D01*
G01X1041228Y163902D02*
Y168902D01*
G01X1051935Y166569D02*
X1052188Y166819D01*
X1052378Y167235D01*
X1052505Y167819D01*
X1052378Y168319D01*
X1052125Y168652D01*
X1051681Y168902D01*
X1049971D01*
Y163902D01*
X1052061D01*
X1052505Y164235D01*
X1052758Y164735D01*
X1052885Y165319D01*
X1052758Y165902D01*
X1052378Y166402D01*
X1051935Y166569D01*
X1049971D01*
G01X1056528Y163902D02*
X1056148Y163985D01*
X1055768Y164319D01*
X1055515Y164902D01*
X1055388Y165569D01*
X1055515Y166235D01*
X1055768Y166819D01*
X1056148Y167152D01*
X1056528Y167235D01*
X1056908Y167152D01*
X1057288Y166819D01*
X1057541Y166235D01*
X1057605Y165569D01*
X1057541Y164902D01*
X1057288Y164319D01*
X1056908Y163985D01*
X1056528Y163902D01*
G01X1062768D02*
Y167235D01*
G01Y166652D02*
X1062515Y166985D01*
X1062135Y167152D01*
X1061691Y167235D01*
X1061248Y167069D01*
X1060868Y166735D01*
X1060615Y166235D01*
X1060488Y165569D01*
X1060615Y164902D01*
X1060868Y164402D01*
X1061248Y164069D01*
X1061691Y163902D01*
X1062135Y163985D01*
X1062515Y164235D01*
X1062768Y164569D01*
G01X1065841Y163902D02*
Y167235D01*
G01Y166569D02*
X1066158Y166902D01*
X1066475Y167152D01*
X1066918Y167235D01*
X1067235Y167152D01*
X1067615Y166902D01*
G01X1072968Y168902D02*
Y163902D01*
G01Y164652D02*
X1072715Y164235D01*
X1072335Y163985D01*
X1071891Y163902D01*
X1071385Y164069D01*
X1071005Y164485D01*
X1070751Y164985D01*
X1070688Y165569D01*
X1070751Y166152D01*
X1071005Y166652D01*
X1071385Y167069D01*
X1071891Y167235D01*
X1072335Y167152D01*
X1072651Y166985D01*
X1072968Y166652D01*
G01X999225Y163902D02*
Y168902D01*
X1001631D01*
G01X1000745Y166485D02*
X999225D01*
G01X1005528Y163902D02*
X1005148Y163985D01*
X1004768Y164319D01*
X1004515Y164902D01*
X1004388Y165569D01*
X1004515Y166235D01*
X1004768Y166819D01*
X1005148Y167152D01*
X1005528Y167235D01*
X1005908Y167152D01*
X1006288Y166819D01*
X1006541Y166235D01*
X1006605Y165569D01*
X1006541Y164902D01*
X1006288Y164319D01*
X1005908Y163985D01*
X1005528Y163902D01*
G01X1009741D02*
Y167235D01*
G01Y166569D02*
X1010058Y166902D01*
X1010375Y167152D01*
X1010818Y167235D01*
X1011135Y167152D01*
X1011515Y166902D01*
G01X1019561Y163902D02*
Y168902D01*
X1021081D01*
X1021588Y168652D01*
X1021968Y168069D01*
X1022095Y167402D01*
X1021968Y166735D01*
X1021651Y166235D01*
X1021081Y165985D01*
X1019561D01*
G01X1027068Y163902D02*
Y167235D01*
G01Y166652D02*
X1026815Y166985D01*
X1026435Y167152D01*
X1025991Y167235D01*
X1025548Y167069D01*
X1025168Y166735D01*
X1024915Y166235D01*
X1024788Y165569D01*
X1024915Y164902D01*
X1025168Y164402D01*
X1025548Y164069D01*
X1025991Y163902D01*
X1026435Y163985D01*
X1026815Y164235D01*
X1027068Y164569D01*
G01X1029951Y163902D02*
Y167235D01*
G01Y166402D02*
X1030205Y166819D01*
X1030585Y167152D01*
X1031091Y167235D01*
X1031535Y167152D01*
X1031915Y166819D01*
X1032105Y166235D01*
Y163902D01*
G01X1035178Y166152D02*
X1037205D01*
X1037015Y166735D01*
X1036698Y167069D01*
X1036255Y167235D01*
X1035811Y167152D01*
X1035431Y166902D01*
X1035178Y166319D01*
X1035051Y165819D01*
Y165319D01*
X1035178Y164819D01*
X1035495Y164319D01*
X1035875Y163985D01*
X1036318Y163902D01*
X1036761Y164069D01*
X1037205Y164569D01*
G01X1041228Y163902D02*
Y168902D01*
G01X1051935Y166569D02*
X1052188Y166819D01*
X1052378Y167235D01*
X1052505Y167819D01*
X1052378Y168319D01*
X1052125Y168652D01*
X1051681Y168902D01*
X1049971D01*
Y163902D01*
X1052061D01*
X1052505Y164235D01*
X1052758Y164735D01*
X1052885Y165319D01*
X1052758Y165902D01*
X1052378Y166402D01*
X1051935Y166569D01*
X1049971D01*
G01X1056528Y163902D02*
X1056148Y163985D01*
X1055768Y164319D01*
X1055515Y164902D01*
X1055388Y165569D01*
X1055515Y166235D01*
X1055768Y166819D01*
X1056148Y167152D01*
X1056528Y167235D01*
X1056908Y167152D01*
X1057288Y166819D01*
X1057541Y166235D01*
X1057605Y165569D01*
X1057541Y164902D01*
X1057288Y164319D01*
X1056908Y163985D01*
X1056528Y163902D01*
G01X1062768D02*
Y167235D01*
G01Y166652D02*
X1062515Y166985D01*
X1062135Y167152D01*
X1061691Y167235D01*
X1061248Y167069D01*
X1060868Y166735D01*
X1060615Y166235D01*
X1060488Y165569D01*
X1060615Y164902D01*
X1060868Y164402D01*
X1061248Y164069D01*
X1061691Y163902D01*
X1062135Y163985D01*
X1062515Y164235D01*
X1062768Y164569D01*
G01X1065841Y163902D02*
Y167235D01*
G01Y166569D02*
X1066158Y166902D01*
X1066475Y167152D01*
X1066918Y167235D01*
X1067235Y167152D01*
X1067615Y166902D01*
G01X1072968Y168902D02*
Y163902D01*
G01Y164652D02*
X1072715Y164235D01*
X1072335Y163985D01*
X1071891Y163902D01*
X1071385Y164069D01*
X1071005Y164485D01*
X1070751Y164985D01*
X1070688Y165569D01*
X1070751Y166152D01*
X1071005Y166652D01*
X1071385Y167069D01*
X1071891Y167235D01*
X1072335Y167152D01*
X1072651Y166985D01*
X1072968Y166652D01*
G01X1000428Y181502D02*
Y176502D01*
G01X998971Y181502D02*
X1001885D01*
G01X1005528Y176502D02*
X1005148Y176585D01*
X1004768Y176919D01*
X1004515Y177502D01*
X1004388Y178169D01*
X1004515Y178835D01*
X1004768Y179419D01*
X1005148Y179752D01*
X1005528Y179835D01*
X1005908Y179752D01*
X1006288Y179419D01*
X1006541Y178835D01*
X1006605Y178169D01*
X1006541Y177502D01*
X1006288Y176919D01*
X1005908Y176585D01*
X1005528Y176502D01*
G01X1009488Y174835D02*
Y179835D01*
G01Y179085D02*
X1009805Y179502D01*
X1010121Y179752D01*
X1010628Y179835D01*
X1011071Y179752D01*
X1011515Y179335D01*
X1011705Y178752D01*
X1011768Y178169D01*
X1011705Y177585D01*
X1011515Y177002D01*
X1011135Y176669D01*
X1010628Y176502D01*
X1010185Y176585D01*
X1009741Y176835D01*
X1009488Y177169D01*
G01X1019245Y176502D02*
X1020828Y181502D01*
X1022411Y176502D01*
G01X1021841Y178252D02*
X1019815D01*
G01X1024851Y176502D02*
Y179835D01*
G01Y179002D02*
X1025105Y179419D01*
X1025485Y179752D01*
X1025991Y179835D01*
X1026435Y179752D01*
X1026815Y179419D01*
X1027005Y178835D01*
Y176502D01*
G01X1032168Y181502D02*
Y176502D01*
G01Y177252D02*
X1031915Y176835D01*
X1031535Y176585D01*
X1031091Y176502D01*
X1030585Y176669D01*
X1030205Y177085D01*
X1029951Y177585D01*
X1029888Y178169D01*
X1029951Y178752D01*
X1030205Y179252D01*
X1030585Y179669D01*
X1031091Y179835D01*
X1031535Y179752D01*
X1031851Y179585D01*
X1032168Y179252D01*
G01X1041735Y179169D02*
X1041988Y179419D01*
X1042178Y179835D01*
X1042305Y180419D01*
X1042178Y180919D01*
X1041925Y181252D01*
X1041481Y181502D01*
X1039771D01*
Y176502D01*
X1041861D01*
X1042305Y176835D01*
X1042558Y177335D01*
X1042685Y177919D01*
X1042558Y178502D01*
X1042178Y179002D01*
X1041735Y179169D01*
X1039771D01*
G01X1046328Y176502D02*
X1045948Y176585D01*
X1045568Y176919D01*
X1045315Y177502D01*
X1045188Y178169D01*
X1045315Y178835D01*
X1045568Y179419D01*
X1045948Y179752D01*
X1046328Y179835D01*
X1046708Y179752D01*
X1047088Y179419D01*
X1047341Y178835D01*
X1047405Y178169D01*
X1047341Y177502D01*
X1047088Y176919D01*
X1046708Y176585D01*
X1046328Y176502D01*
G01X1051428Y181502D02*
Y176502D01*
G01X1050541Y179835D02*
X1052315D01*
G01X1056528Y181502D02*
Y176502D01*
G01X1055641Y179835D02*
X1057415D01*
G01X1061628Y176502D02*
X1061248Y176585D01*
X1060868Y176919D01*
X1060615Y177502D01*
X1060488Y178169D01*
X1060615Y178835D01*
X1060868Y179419D01*
X1061248Y179752D01*
X1061628Y179835D01*
X1062008Y179752D01*
X1062388Y179419D01*
X1062641Y178835D01*
X1062705Y178169D01*
X1062641Y177502D01*
X1062388Y176919D01*
X1062008Y176585D01*
X1061628Y176502D01*
G01X1064828D02*
Y179835D01*
G01Y178919D02*
X1065018Y179335D01*
X1065335Y179669D01*
X1065778Y179835D01*
X1066221Y179669D01*
X1066538Y179335D01*
X1066728Y178919D01*
Y176502D01*
G01Y178919D02*
X1066918Y179335D01*
X1067235Y179669D01*
X1067678Y179835D01*
X1068121Y179669D01*
X1068438Y179335D01*
X1068628Y178835D01*
Y176502D01*
G01X1075598Y177169D02*
X1076105Y176752D01*
X1076675Y176502D01*
X1077181D01*
X1077688Y176752D01*
X1078068Y177169D01*
X1078258Y177752D01*
X1078131Y178335D01*
X1077815Y178835D01*
X1077245Y179169D01*
X1076485Y179335D01*
X1076041Y179669D01*
X1075851Y180252D01*
X1075978Y180835D01*
X1076295Y181252D01*
X1076738Y181502D01*
X1077181D01*
X1077625Y181335D01*
X1078005Y180919D01*
G01X1082028Y179835D02*
Y176502D01*
G01Y181169D02*
X1081901Y181252D01*
Y181419D01*
X1082028Y181502D01*
X1082155Y181419D01*
Y181252D01*
X1082028Y181169D01*
G01X1088268Y181502D02*
Y176502D01*
G01Y177252D02*
X1088015Y176835D01*
X1087635Y176585D01*
X1087191Y176502D01*
X1086685Y176669D01*
X1086305Y177085D01*
X1086051Y177585D01*
X1085988Y178169D01*
X1086051Y178752D01*
X1086305Y179252D01*
X1086685Y179669D01*
X1087191Y179835D01*
X1087635Y179752D01*
X1087951Y179585D01*
X1088268Y179252D01*
G01X1091278Y178752D02*
X1093305D01*
X1093115Y179335D01*
X1092798Y179669D01*
X1092355Y179835D01*
X1091911Y179752D01*
X1091531Y179502D01*
X1091278Y178919D01*
X1091151Y178419D01*
Y177919D01*
X1091278Y177419D01*
X1091595Y176919D01*
X1091975Y176585D01*
X1092418Y176502D01*
X1092861Y176669D01*
X1093305Y177169D01*
G01X922725Y201702D02*
Y206702D01*
X925131D01*
G01X924245Y204285D02*
X922725D01*
G01X929028Y205035D02*
Y201702D01*
G01Y206369D02*
X928901Y206452D01*
Y206619D01*
X929028Y206702D01*
X929155Y206619D01*
Y206452D01*
X929028Y206369D01*
G01X935268Y206702D02*
Y201702D01*
G01Y202452D02*
X935015Y202035D01*
X934635Y201785D01*
X934191Y201702D01*
X933685Y201869D01*
X933305Y202285D01*
X933051Y202785D01*
X932988Y203369D01*
X933051Y203952D01*
X933305Y204452D01*
X933685Y204869D01*
X934191Y205035D01*
X934635Y204952D01*
X934951Y204785D01*
X935268Y204452D01*
G01X938151Y205035D02*
Y202702D01*
X938405Y202119D01*
X938785Y201785D01*
X939228Y201702D01*
X939671Y201785D01*
X940051Y202119D01*
X940305Y202702D01*
G01Y201702D02*
Y205035D01*
G01X945341Y204619D02*
X944898Y204952D01*
X944518Y205035D01*
X944011Y204869D01*
X943631Y204535D01*
X943378Y203952D01*
X943315Y203369D01*
X943378Y202785D01*
X943631Y202285D01*
X944011Y201869D01*
X944518Y201702D01*
X944961Y201869D01*
X945341Y202202D01*
G01X949428Y205035D02*
Y201702D01*
G01Y206369D02*
X949301Y206452D01*
Y206619D01*
X949428Y206702D01*
X949555Y206619D01*
Y206452D01*
X949428Y206369D01*
G01X955668Y201702D02*
Y205035D01*
G01Y204452D02*
X955415Y204785D01*
X955035Y204952D01*
X954591Y205035D01*
X954148Y204869D01*
X953768Y204535D01*
X953515Y204035D01*
X953388Y203369D01*
X953515Y202702D01*
X953768Y202202D01*
X954148Y201869D01*
X954591Y201702D01*
X955035Y201785D01*
X955415Y202035D01*
X955668Y202369D01*
G01X959628Y201702D02*
Y206702D01*
G01X968181Y201702D02*
Y206702D01*
X969828Y202535D01*
X971475Y206702D01*
Y201702D01*
G01X976068D02*
Y205035D01*
G01Y204452D02*
X975815Y204785D01*
X975435Y204952D01*
X974991Y205035D01*
X974548Y204869D01*
X974168Y204535D01*
X973915Y204035D01*
X973788Y203369D01*
X973915Y202702D01*
X974168Y202202D01*
X974548Y201869D01*
X974991Y201702D01*
X975435Y201785D01*
X975815Y202035D01*
X976068Y202369D01*
G01X979141Y201702D02*
Y205035D01*
G01Y204369D02*
X979458Y204702D01*
X979775Y204952D01*
X980218Y205035D01*
X980535Y204952D01*
X980915Y204702D01*
G01X984051Y201702D02*
Y206702D01*
G01X986078Y205035D02*
X984051Y203119D01*
G01X984875Y203869D02*
X986205Y201702D01*
G01X990228Y201535D02*
X990101Y201619D01*
Y201785D01*
X990228Y201869D01*
X990355Y201785D01*
Y201619D01*
X990228Y201535D01*
G01Y203785D02*
X990101Y203869D01*
Y204035D01*
X990228Y204119D01*
X990355Y204035D01*
Y203869D01*
X990228Y203785D01*
G01X999035Y201702D02*
Y206702D01*
X1000301D01*
X1000808Y206452D01*
X1001188Y206119D01*
X1001505Y205619D01*
X1001758Y205035D01*
X1001821Y204202D01*
X1001758Y203369D01*
X1001505Y202785D01*
X1001188Y202285D01*
X1000808Y201952D01*
X1000301Y201702D01*
X999035D01*
G01X1005528Y205035D02*
Y201702D01*
G01Y206369D02*
X1005401Y206452D01*
Y206619D01*
X1005528Y206702D01*
X1005655Y206619D01*
Y206452D01*
X1005528Y206369D01*
G01X1011768Y201702D02*
Y205035D01*
G01Y204452D02*
X1011515Y204785D01*
X1011135Y204952D01*
X1010691Y205035D01*
X1010248Y204869D01*
X1009868Y204535D01*
X1009615Y204035D01*
X1009488Y203369D01*
X1009615Y202702D01*
X1009868Y202202D01*
X1010248Y201869D01*
X1010691Y201702D01*
X1011135Y201785D01*
X1011515Y202035D01*
X1011768Y202369D01*
G01X1013828Y201702D02*
Y205035D01*
G01Y204119D02*
X1014018Y204535D01*
X1014335Y204869D01*
X1014778Y205035D01*
X1015221Y204869D01*
X1015538Y204535D01*
X1015728Y204119D01*
Y201702D01*
G01Y204119D02*
X1015918Y204535D01*
X1016235Y204869D01*
X1016678Y205035D01*
X1017121Y204869D01*
X1017438Y204535D01*
X1017628Y204035D01*
Y201702D01*
G01X1019878Y203952D02*
X1021905D01*
X1021715Y204535D01*
X1021398Y204869D01*
X1020955Y205035D01*
X1020511Y204952D01*
X1020131Y204702D01*
X1019878Y204119D01*
X1019751Y203619D01*
Y203119D01*
X1019878Y202619D01*
X1020195Y202119D01*
X1020575Y201785D01*
X1021018Y201702D01*
X1021461Y201869D01*
X1021905Y202369D01*
G01X1025928Y206702D02*
Y201702D01*
G01X1025041Y205035D02*
X1026815D01*
G01X1030078Y203952D02*
X1032105D01*
X1031915Y204535D01*
X1031598Y204869D01*
X1031155Y205035D01*
X1030711Y204952D01*
X1030331Y204702D01*
X1030078Y204119D01*
X1029951Y203619D01*
Y203119D01*
X1030078Y202619D01*
X1030395Y202119D01*
X1030775Y201785D01*
X1031218Y201702D01*
X1031661Y201869D01*
X1032105Y202369D01*
G01X1035241Y201702D02*
Y205035D01*
G01Y204369D02*
X1035558Y204702D01*
X1035875Y204952D01*
X1036318Y205035D01*
X1036635Y204952D01*
X1037015Y204702D01*
G01X1046328Y201702D02*
Y206702D01*
X1045568Y205702D01*
G01Y201702D02*
X1047088D01*
G01X1049528D02*
Y205035D01*
G01Y204119D02*
X1049718Y204535D01*
X1050035Y204869D01*
X1050478Y205035D01*
X1050921Y204869D01*
X1051238Y204535D01*
X1051428Y204119D01*
Y201702D01*
G01Y204119D02*
X1051618Y204535D01*
X1051935Y204869D01*
X1052378Y205035D01*
X1052821Y204869D01*
X1053138Y204535D01*
X1053328Y204035D01*
Y201702D01*
G01X1054628D02*
Y205035D01*
G01Y204119D02*
X1054818Y204535D01*
X1055135Y204869D01*
X1055578Y205035D01*
X1056021Y204869D01*
X1056338Y204535D01*
X1056528Y204119D01*
Y201702D01*
G01Y204119D02*
X1056718Y204535D01*
X1057035Y204869D01*
X1057478Y205035D01*
X1057921Y204869D01*
X1058238Y204535D01*
X1058428Y204035D01*
Y201702D01*
G01X1068121Y206285D02*
X1067741Y206535D01*
X1067298Y206702D01*
X1066791D01*
X1066221Y206452D01*
X1065778Y206035D01*
X1065461Y205535D01*
X1065208Y204702D01*
X1065145Y203952D01*
X1065271Y203202D01*
X1065461Y202702D01*
X1065841Y202202D01*
X1066285Y201869D01*
X1066728Y201702D01*
X1067171D01*
X1067615Y201869D01*
X1067995Y202119D01*
X1068311Y202452D01*
G01X1071828Y201702D02*
X1071448Y201785D01*
X1071068Y202119D01*
X1070815Y202702D01*
X1070688Y203369D01*
X1070815Y204035D01*
X1071068Y204619D01*
X1071448Y204952D01*
X1071828Y205035D01*
X1072208Y204952D01*
X1072588Y204619D01*
X1072841Y204035D01*
X1072905Y203369D01*
X1072841Y202702D01*
X1072588Y202119D01*
X1072208Y201785D01*
X1071828Y201702D01*
G01X1075788Y200035D02*
Y205035D01*
G01Y204285D02*
X1076105Y204702D01*
X1076421Y204952D01*
X1076928Y205035D01*
X1077371Y204952D01*
X1077815Y204535D01*
X1078005Y203952D01*
X1078068Y203369D01*
X1078005Y202785D01*
X1077815Y202202D01*
X1077435Y201869D01*
X1076928Y201702D01*
X1076485Y201785D01*
X1076041Y202035D01*
X1075788Y202369D01*
G01X1080888Y200035D02*
Y205035D01*
G01Y204285D02*
X1081205Y204702D01*
X1081521Y204952D01*
X1082028Y205035D01*
X1082471Y204952D01*
X1082915Y204535D01*
X1083105Y203952D01*
X1083168Y203369D01*
X1083105Y202785D01*
X1082915Y202202D01*
X1082535Y201869D01*
X1082028Y201702D01*
X1081585Y201785D01*
X1081141Y202035D01*
X1080888Y202369D01*
G01X1086178Y203952D02*
X1088205D01*
X1088015Y204535D01*
X1087698Y204869D01*
X1087255Y205035D01*
X1086811Y204952D01*
X1086431Y204702D01*
X1086178Y204119D01*
X1086051Y203619D01*
Y203119D01*
X1086178Y202619D01*
X1086495Y202119D01*
X1086875Y201785D01*
X1087318Y201702D01*
X1087761Y201869D01*
X1088205Y202369D01*
G01X1091341Y201702D02*
Y205035D01*
G01Y204369D02*
X1091658Y204702D01*
X1091975Y204952D01*
X1092418Y205035D01*
X1092735Y204952D01*
X1093115Y204702D01*
G01X999035Y189102D02*
Y194102D01*
X1000301D01*
X1000808Y193852D01*
X1001188Y193519D01*
X1001505Y193019D01*
X1001758Y192435D01*
X1001821Y191602D01*
X1001758Y190769D01*
X1001505Y190185D01*
X1001188Y189685D01*
X1000808Y189352D01*
X1000301Y189102D01*
X999035D01*
G01X1005528Y192435D02*
Y189102D01*
G01Y193769D02*
X1005401Y193852D01*
Y194019D01*
X1005528Y194102D01*
X1005655Y194019D01*
Y193852D01*
X1005528Y193769D01*
G01X1011768Y189102D02*
Y192435D01*
G01Y191852D02*
X1011515Y192185D01*
X1011135Y192352D01*
X1010691Y192435D01*
X1010248Y192269D01*
X1009868Y191935D01*
X1009615Y191435D01*
X1009488Y190769D01*
X1009615Y190102D01*
X1009868Y189602D01*
X1010248Y189269D01*
X1010691Y189102D01*
X1011135Y189185D01*
X1011515Y189435D01*
X1011768Y189769D01*
G01X1013828Y189102D02*
Y192435D01*
G01Y191519D02*
X1014018Y191935D01*
X1014335Y192269D01*
X1014778Y192435D01*
X1015221Y192269D01*
X1015538Y191935D01*
X1015728Y191519D01*
Y189102D01*
G01Y191519D02*
X1015918Y191935D01*
X1016235Y192269D01*
X1016678Y192435D01*
X1017121Y192269D01*
X1017438Y191935D01*
X1017628Y191435D01*
Y189102D01*
G01X1019878Y191352D02*
X1021905D01*
X1021715Y191935D01*
X1021398Y192269D01*
X1020955Y192435D01*
X1020511Y192352D01*
X1020131Y192102D01*
X1019878Y191519D01*
X1019751Y191019D01*
Y190519D01*
X1019878Y190019D01*
X1020195Y189519D01*
X1020575Y189185D01*
X1021018Y189102D01*
X1021461Y189269D01*
X1021905Y189769D01*
G01X1025928Y194102D02*
Y189102D01*
G01X1025041Y192435D02*
X1026815D01*
G01X1030078Y191352D02*
X1032105D01*
X1031915Y191935D01*
X1031598Y192269D01*
X1031155Y192435D01*
X1030711Y192352D01*
X1030331Y192102D01*
X1030078Y191519D01*
X1029951Y191019D01*
Y190519D01*
X1030078Y190019D01*
X1030395Y189519D01*
X1030775Y189185D01*
X1031218Y189102D01*
X1031661Y189269D01*
X1032105Y189769D01*
G01X1035241Y189102D02*
Y192435D01*
G01Y191769D02*
X1035558Y192102D01*
X1035875Y192352D01*
X1036318Y192435D01*
X1036635Y192352D01*
X1037015Y192102D01*
G01X1044935Y190102D02*
X1045315Y189519D01*
X1045821Y189185D01*
X1046391Y189102D01*
X1046898Y189185D01*
X1047405Y189602D01*
X1047721Y190102D01*
X1047785Y190602D01*
X1047658Y191185D01*
X1047215Y191602D01*
X1046771Y191769D01*
X1046201D01*
G01X1046771D02*
X1047151Y192019D01*
X1047468Y192435D01*
X1047595Y192935D01*
X1047468Y193435D01*
X1047151Y193852D01*
X1046581Y194102D01*
X1046011Y194019D01*
X1045441Y193685D01*
G01X1049528Y189102D02*
Y192435D01*
G01Y191519D02*
X1049718Y191935D01*
X1050035Y192269D01*
X1050478Y192435D01*
X1050921Y192269D01*
X1051238Y191935D01*
X1051428Y191519D01*
Y189102D01*
G01Y191519D02*
X1051618Y191935D01*
X1051935Y192269D01*
X1052378Y192435D01*
X1052821Y192269D01*
X1053138Y191935D01*
X1053328Y191435D01*
Y189102D01*
G01X1054628D02*
Y192435D01*
G01Y191519D02*
X1054818Y191935D01*
X1055135Y192269D01*
X1055578Y192435D01*
X1056021Y192269D01*
X1056338Y191935D01*
X1056528Y191519D01*
Y189102D01*
G01Y191519D02*
X1056718Y191935D01*
X1057035Y192269D01*
X1057478Y192435D01*
X1057921Y192269D01*
X1058238Y191935D01*
X1058428Y191435D01*
Y189102D01*
G01X1065398Y189769D02*
X1065905Y189352D01*
X1066475Y189102D01*
X1066981D01*
X1067488Y189352D01*
X1067868Y189769D01*
X1068058Y190352D01*
X1067931Y190935D01*
X1067615Y191435D01*
X1067045Y191769D01*
X1066285Y191935D01*
X1065841Y192269D01*
X1065651Y192852D01*
X1065778Y193435D01*
X1066095Y193852D01*
X1066538Y194102D01*
X1066981D01*
X1067425Y193935D01*
X1067805Y193519D01*
G01X1071828Y189102D02*
X1071448Y189185D01*
X1071068Y189519D01*
X1070815Y190102D01*
X1070688Y190769D01*
X1070815Y191435D01*
X1071068Y192019D01*
X1071448Y192352D01*
X1071828Y192435D01*
X1072208Y192352D01*
X1072588Y192019D01*
X1072841Y191435D01*
X1072905Y190769D01*
X1072841Y190102D01*
X1072588Y189519D01*
X1072208Y189185D01*
X1071828Y189102D01*
G01X1076928D02*
Y194102D01*
G01X1083168D02*
Y189102D01*
G01Y189852D02*
X1082915Y189435D01*
X1082535Y189185D01*
X1082091Y189102D01*
X1081585Y189269D01*
X1081205Y189685D01*
X1080951Y190185D01*
X1080888Y190769D01*
X1080951Y191352D01*
X1081205Y191852D01*
X1081585Y192269D01*
X1082091Y192435D01*
X1082535Y192352D01*
X1082851Y192185D01*
X1083168Y191852D01*
G01X1086178Y191352D02*
X1088205D01*
X1088015Y191935D01*
X1087698Y192269D01*
X1087255Y192435D01*
X1086811Y192352D01*
X1086431Y192102D01*
X1086178Y191519D01*
X1086051Y191019D01*
Y190519D01*
X1086178Y190019D01*
X1086495Y189519D01*
X1086875Y189185D01*
X1087318Y189102D01*
X1087761Y189269D01*
X1088205Y189769D01*
G01X1091341Y189102D02*
Y192435D01*
G01Y191769D02*
X1091658Y192102D01*
X1091975Y192352D01*
X1092418Y192435D01*
X1092735Y192352D01*
X1093115Y192102D01*
G01X1095428Y189102D02*
Y192435D01*
G01Y191519D02*
X1095618Y191935D01*
X1095935Y192269D01*
X1096378Y192435D01*
X1096821Y192269D01*
X1097138Y191935D01*
X1097328Y191519D01*
Y189102D01*
G01Y191519D02*
X1097518Y191935D01*
X1097835Y192269D01*
X1098278Y192435D01*
X1098721Y192269D01*
X1099038Y191935D01*
X1099228Y191435D01*
Y189102D01*
G01X1103568D02*
Y192435D01*
G01Y191852D02*
X1103315Y192185D01*
X1102935Y192352D01*
X1102491Y192435D01*
X1102048Y192269D01*
X1101668Y191935D01*
X1101415Y191435D01*
X1101288Y190769D01*
X1101415Y190102D01*
X1101668Y189602D01*
X1102048Y189269D01*
X1102491Y189102D01*
X1102935Y189185D01*
X1103315Y189435D01*
X1103568Y189769D01*
G01X1106578Y189685D02*
X1106895Y189352D01*
X1107338Y189102D01*
X1107718D01*
X1108098Y189269D01*
X1108351Y189519D01*
X1108478Y189852D01*
X1108415Y190352D01*
X1108161Y190602D01*
X1107021Y191102D01*
X1106768Y191685D01*
X1106895Y192102D01*
X1107148Y192352D01*
X1107528Y192435D01*
X1107908Y192352D01*
X1108288Y192102D01*
G01X1111551Y189102D02*
Y194102D01*
G01X1113578Y192435D02*
X1111551Y190519D01*
G01X1112375Y191269D02*
X1113705Y189102D01*
G01X996116Y263393D02*
Y258393D01*
G01X994659Y263393D02*
X997573D01*
G01X1001216Y258393D02*
X1000836Y258476D01*
X1000456Y258810D01*
X1000203Y259393D01*
X1000076Y260060D01*
X1000203Y260726D01*
X1000456Y261310D01*
X1000836Y261643D01*
X1001216Y261726D01*
X1001596Y261643D01*
X1001976Y261310D01*
X1002229Y260726D01*
X1002293Y260060D01*
X1002229Y259393D01*
X1001976Y258810D01*
X1001596Y258476D01*
X1001216Y258393D01*
G01X1006316D02*
Y263393D01*
G01X1010466Y260643D02*
X1012493D01*
X1012303Y261226D01*
X1011986Y261560D01*
X1011543Y261726D01*
X1011099Y261643D01*
X1010719Y261393D01*
X1010466Y260810D01*
X1010339Y260310D01*
Y259810D01*
X1010466Y259310D01*
X1010783Y258810D01*
X1011163Y258476D01*
X1011606Y258393D01*
X1012049Y258560D01*
X1012493Y259060D01*
G01X1015629Y258393D02*
Y261726D01*
G01Y261060D02*
X1015946Y261393D01*
X1016263Y261643D01*
X1016706Y261726D01*
X1017023Y261643D01*
X1017403Y261393D01*
G01X1022756Y258393D02*
Y261726D01*
G01Y261143D02*
X1022503Y261476D01*
X1022123Y261643D01*
X1021679Y261726D01*
X1021236Y261560D01*
X1020856Y261226D01*
X1020603Y260726D01*
X1020476Y260060D01*
X1020603Y259393D01*
X1020856Y258893D01*
X1021236Y258560D01*
X1021679Y258393D01*
X1022123Y258476D01*
X1022503Y258726D01*
X1022756Y259060D01*
G01X1025639Y258393D02*
Y261726D01*
G01Y260893D02*
X1025893Y261310D01*
X1026273Y261643D01*
X1026779Y261726D01*
X1027223Y261643D01*
X1027603Y261310D01*
X1027793Y260726D01*
Y258393D01*
G01X1032829Y261310D02*
X1032386Y261643D01*
X1032006Y261726D01*
X1031499Y261560D01*
X1031119Y261226D01*
X1030866Y260643D01*
X1030803Y260060D01*
X1030866Y259476D01*
X1031119Y258976D01*
X1031499Y258560D01*
X1032006Y258393D01*
X1032449Y258560D01*
X1032829Y258893D01*
G01X1035966Y260643D02*
X1037993D01*
X1037803Y261226D01*
X1037486Y261560D01*
X1037043Y261726D01*
X1036599Y261643D01*
X1036219Y261393D01*
X1035966Y260810D01*
X1035839Y260310D01*
Y259810D01*
X1035966Y259310D01*
X1036283Y258810D01*
X1036663Y258476D01*
X1037106Y258393D01*
X1037549Y258560D01*
X1037993Y259060D01*
G01X1046419Y260060D02*
X1047939D01*
G01X1047116Y261143D02*
Y258976D01*
G01X1052216Y263393D02*
X1051709Y263226D01*
X1051329Y262810D01*
X1051076Y262310D01*
X1050886Y261643D01*
X1050823Y260893D01*
X1050886Y260143D01*
X1051076Y259476D01*
X1051329Y258976D01*
X1051709Y258560D01*
X1052216Y258393D01*
X1052723Y258560D01*
X1053103Y258976D01*
X1053356Y259476D01*
X1053546Y260143D01*
X1053609Y260893D01*
X1053546Y261643D01*
X1053356Y262310D01*
X1053103Y262810D01*
X1052723Y263226D01*
X1052216Y263393D01*
G01X1057316Y258226D02*
X1057189Y258310D01*
Y258476D01*
X1057316Y258560D01*
X1057443Y258476D01*
Y258310D01*
X1057316Y258226D01*
G01X1062416Y263393D02*
X1061909Y263226D01*
X1061529Y262810D01*
X1061276Y262310D01*
X1061086Y261643D01*
X1061023Y260893D01*
X1061086Y260143D01*
X1061276Y259476D01*
X1061529Y258976D01*
X1061909Y258560D01*
X1062416Y258393D01*
X1062923Y258560D01*
X1063303Y258976D01*
X1063556Y259476D01*
X1063746Y260143D01*
X1063809Y260893D01*
X1063746Y261643D01*
X1063556Y262310D01*
X1063303Y262810D01*
X1062923Y263226D01*
X1062416Y263393D01*
G01X1066123Y259143D02*
X1066503Y258726D01*
X1066946Y258476D01*
X1067516Y258393D01*
X1068086Y258560D01*
X1068529Y258893D01*
X1068846Y259476D01*
X1068909Y260143D01*
X1068783Y260810D01*
X1068466Y261226D01*
X1068023Y261560D01*
X1067579Y261643D01*
X1067136Y261560D01*
X1066566Y261226D01*
X1066756Y263393D01*
X1068466D01*
G01X1072616D02*
X1072109Y263226D01*
X1071729Y262810D01*
X1071476Y262310D01*
X1071286Y261643D01*
X1071223Y260893D01*
X1071286Y260143D01*
X1071476Y259476D01*
X1071729Y258976D01*
X1072109Y258560D01*
X1072616Y258393D01*
X1073123Y258560D01*
X1073503Y258976D01*
X1073756Y259476D01*
X1073946Y260143D01*
X1074009Y260893D01*
X1073946Y261643D01*
X1073756Y262310D01*
X1073503Y262810D01*
X1073123Y263226D01*
X1072616Y263393D01*
G01X1077716Y258393D02*
X1078159Y258476D01*
X1078666Y258726D01*
X1078983Y259143D01*
X1079109Y259726D01*
X1078983Y260310D01*
X1078603Y260810D01*
X1078033Y261060D01*
X1077399D01*
X1077019Y261226D01*
X1076703Y261643D01*
X1076576Y262226D01*
X1076766Y262810D01*
X1077209Y263226D01*
X1077716Y263393D01*
X1078223Y263226D01*
X1078666Y262810D01*
X1078856Y262226D01*
X1078729Y261643D01*
X1078413Y261226D01*
X1078033Y261060D01*
X1077399D01*
X1076829Y260810D01*
X1076449Y260310D01*
X1076323Y259726D01*
X1076449Y259143D01*
X1076766Y258726D01*
X1077273Y258476D01*
X1077716Y258393D01*
G01X1080916D02*
Y261726D01*
G01Y260810D02*
X1081106Y261226D01*
X1081423Y261560D01*
X1081866Y261726D01*
X1082309Y261560D01*
X1082626Y261226D01*
X1082816Y260810D01*
Y258393D01*
G01Y260810D02*
X1083006Y261226D01*
X1083323Y261560D01*
X1083766Y261726D01*
X1084209Y261560D01*
X1084526Y261226D01*
X1084716Y260726D01*
Y258393D01*
G01X1086016D02*
Y261726D01*
G01Y260810D02*
X1086206Y261226D01*
X1086523Y261560D01*
X1086966Y261726D01*
X1087409Y261560D01*
X1087726Y261226D01*
X1087916Y260810D01*
Y258393D01*
G01Y260810D02*
X1088106Y261226D01*
X1088423Y261560D01*
X1088866Y261726D01*
X1089309Y261560D01*
X1089626Y261226D01*
X1089816Y260726D01*
Y258393D01*
G01X1091876Y258226D02*
X1094156Y263393D01*
G01X1097293Y260060D02*
X1098939D01*
G01X1103216Y263393D02*
X1102709Y263226D01*
X1102329Y262810D01*
X1102076Y262310D01*
X1101886Y261643D01*
X1101823Y260893D01*
X1101886Y260143D01*
X1102076Y259476D01*
X1102329Y258976D01*
X1102709Y258560D01*
X1103216Y258393D01*
X1103723Y258560D01*
X1104103Y258976D01*
X1104356Y259476D01*
X1104546Y260143D01*
X1104609Y260893D01*
X1104546Y261643D01*
X1104356Y262310D01*
X1104103Y262810D01*
X1103723Y263226D01*
X1103216Y263393D01*
G01X1108316Y258226D02*
X1108189Y258310D01*
Y258476D01*
X1108316Y258560D01*
X1108443Y258476D01*
Y258310D01*
X1108316Y258226D01*
G01X1113416Y263393D02*
X1112909Y263226D01*
X1112529Y262810D01*
X1112276Y262310D01*
X1112086Y261643D01*
X1112023Y260893D01*
X1112086Y260143D01*
X1112276Y259476D01*
X1112529Y258976D01*
X1112909Y258560D01*
X1113416Y258393D01*
X1113923Y258560D01*
X1114303Y258976D01*
X1114556Y259476D01*
X1114746Y260143D01*
X1114809Y260893D01*
X1114746Y261643D01*
X1114556Y262310D01*
X1114303Y262810D01*
X1113923Y263226D01*
X1113416Y263393D01*
G01X1117313Y262560D02*
X1117693Y263060D01*
X1118136Y263310D01*
X1118643Y263393D01*
X1119276Y263226D01*
X1119719Y262810D01*
X1119846Y262310D01*
X1119783Y261810D01*
X1119529Y261393D01*
X1118263Y260560D01*
X1117693Y259976D01*
X1117313Y259143D01*
X1117186Y258393D01*
X1119846D01*
G01X1122223Y259143D02*
X1122603Y258726D01*
X1123046Y258476D01*
X1123616Y258393D01*
X1124186Y258560D01*
X1124629Y258893D01*
X1124946Y259476D01*
X1125009Y260143D01*
X1124883Y260810D01*
X1124566Y261226D01*
X1124123Y261560D01*
X1123679Y261643D01*
X1123236Y261560D01*
X1122666Y261226D01*
X1122856Y263393D01*
X1124566D01*
G01X1129476Y258393D02*
Y263393D01*
X1127133Y259810D01*
X1130299D01*
G01X1131916Y258393D02*
Y261726D01*
G01Y260810D02*
X1132106Y261226D01*
X1132423Y261560D01*
X1132866Y261726D01*
X1133309Y261560D01*
X1133626Y261226D01*
X1133816Y260810D01*
Y258393D01*
G01Y260810D02*
X1134006Y261226D01*
X1134323Y261560D01*
X1134766Y261726D01*
X1135209Y261560D01*
X1135526Y261226D01*
X1135716Y260726D01*
Y258393D01*
G01X1137016D02*
Y261726D01*
G01Y260810D02*
X1137206Y261226D01*
X1137523Y261560D01*
X1137966Y261726D01*
X1138409Y261560D01*
X1138726Y261226D01*
X1138916Y260810D01*
Y258393D01*
G01Y260810D02*
X1139106Y261226D01*
X1139423Y261560D01*
X1139866Y261726D01*
X1140309Y261560D01*
X1140626Y261226D01*
X1140816Y260726D01*
Y258393D01*
G01X924716Y275993D02*
Y270993D01*
G01X923259Y275993D02*
X926173D01*
G01X929816Y270993D02*
X929436Y271076D01*
X929056Y271410D01*
X928803Y271993D01*
X928676Y272660D01*
X928803Y273326D01*
X929056Y273910D01*
X929436Y274243D01*
X929816Y274326D01*
X930196Y274243D01*
X930576Y273910D01*
X930829Y273326D01*
X930893Y272660D01*
X930829Y271993D01*
X930576Y271410D01*
X930196Y271076D01*
X929816Y270993D01*
G01X934916D02*
X934536Y271076D01*
X934156Y271410D01*
X933903Y271993D01*
X933776Y272660D01*
X933903Y273326D01*
X934156Y273910D01*
X934536Y274243D01*
X934916Y274326D01*
X935296Y274243D01*
X935676Y273910D01*
X935929Y273326D01*
X935993Y272660D01*
X935929Y271993D01*
X935676Y271410D01*
X935296Y271076D01*
X934916Y270993D01*
G01X940016D02*
Y275993D01*
G01X945116Y274326D02*
Y270993D01*
G01Y275660D02*
X944989Y275743D01*
Y275910D01*
X945116Y275993D01*
X945243Y275910D01*
Y275743D01*
X945116Y275660D01*
G01X949139Y270993D02*
Y274326D01*
G01Y273493D02*
X949393Y273910D01*
X949773Y274243D01*
X950279Y274326D01*
X950723Y274243D01*
X951103Y273910D01*
X951293Y273326D01*
Y270993D01*
G01X954429Y269743D02*
X954873Y269410D01*
X955379Y269326D01*
X955823Y269410D01*
X956203Y269826D01*
X956456Y270410D01*
Y274326D01*
G01Y273660D02*
X956203Y273993D01*
X955823Y274243D01*
X955379Y274326D01*
X954873Y274160D01*
X954556Y273826D01*
X954303Y273243D01*
X954176Y272660D01*
X954239Y272160D01*
X954493Y271576D01*
X954873Y271160D01*
X955379Y270993D01*
X955759Y271076D01*
X956203Y271410D01*
X956456Y271743D01*
G01X964186Y270993D02*
Y275993D01*
G01X966846D02*
Y270993D01*
G01Y273493D02*
X964186D01*
G01X970616Y270993D02*
X970236Y271076D01*
X969856Y271410D01*
X969603Y271993D01*
X969476Y272660D01*
X969603Y273326D01*
X969856Y273910D01*
X970236Y274243D01*
X970616Y274326D01*
X970996Y274243D01*
X971376Y273910D01*
X971629Y273326D01*
X971693Y272660D01*
X971629Y271993D01*
X971376Y271410D01*
X970996Y271076D01*
X970616Y270993D01*
G01X975716D02*
Y275993D01*
G01X979866Y273243D02*
X981893D01*
X981703Y273826D01*
X981386Y274160D01*
X980943Y274326D01*
X980499Y274243D01*
X980119Y273993D01*
X979866Y273410D01*
X979739Y272910D01*
Y272410D01*
X979866Y271910D01*
X980183Y271410D01*
X980563Y271076D01*
X981006Y270993D01*
X981449Y271160D01*
X981893Y271660D01*
G01X985916Y270826D02*
X985789Y270910D01*
Y271076D01*
X985916Y271160D01*
X986043Y271076D01*
Y270910D01*
X985916Y270826D01*
G01Y273076D02*
X985789Y273160D01*
Y273326D01*
X985916Y273410D01*
X986043Y273326D01*
Y273160D01*
X985916Y273076D01*
G01X994723Y270993D02*
Y275993D01*
X995989D01*
X996496Y275743D01*
X996876Y275410D01*
X997193Y274910D01*
X997446Y274326D01*
X997509Y273493D01*
X997446Y272660D01*
X997193Y272076D01*
X996876Y271576D01*
X996496Y271243D01*
X995989Y270993D01*
X994723D01*
G01X1001216Y274326D02*
Y270993D01*
G01Y275660D02*
X1001089Y275743D01*
Y275910D01*
X1001216Y275993D01*
X1001343Y275910D01*
Y275743D01*
X1001216Y275660D01*
G01X1007456Y270993D02*
Y274326D01*
G01Y273743D02*
X1007203Y274076D01*
X1006823Y274243D01*
X1006379Y274326D01*
X1005936Y274160D01*
X1005556Y273826D01*
X1005303Y273326D01*
X1005176Y272660D01*
X1005303Y271993D01*
X1005556Y271493D01*
X1005936Y271160D01*
X1006379Y270993D01*
X1006823Y271076D01*
X1007203Y271326D01*
X1007456Y271660D01*
G01X1009516Y270993D02*
Y274326D01*
G01Y273410D02*
X1009706Y273826D01*
X1010023Y274160D01*
X1010466Y274326D01*
X1010909Y274160D01*
X1011226Y273826D01*
X1011416Y273410D01*
Y270993D01*
G01Y273410D02*
X1011606Y273826D01*
X1011923Y274160D01*
X1012366Y274326D01*
X1012809Y274160D01*
X1013126Y273826D01*
X1013316Y273326D01*
Y270993D01*
G01X1015566Y273243D02*
X1017593D01*
X1017403Y273826D01*
X1017086Y274160D01*
X1016643Y274326D01*
X1016199Y274243D01*
X1015819Y273993D01*
X1015566Y273410D01*
X1015439Y272910D01*
Y272410D01*
X1015566Y271910D01*
X1015883Y271410D01*
X1016263Y271076D01*
X1016706Y270993D01*
X1017149Y271160D01*
X1017593Y271660D01*
G01X1021616Y275993D02*
Y270993D01*
G01X1020729Y274326D02*
X1022503D01*
G01X1025766Y273243D02*
X1027793D01*
X1027603Y273826D01*
X1027286Y274160D01*
X1026843Y274326D01*
X1026399Y274243D01*
X1026019Y273993D01*
X1025766Y273410D01*
X1025639Y272910D01*
Y272410D01*
X1025766Y271910D01*
X1026083Y271410D01*
X1026463Y271076D01*
X1026906Y270993D01*
X1027349Y271160D01*
X1027793Y271660D01*
G01X1030929Y270993D02*
Y274326D01*
G01Y273660D02*
X1031246Y273993D01*
X1031563Y274243D01*
X1032006Y274326D01*
X1032323Y274243D01*
X1032703Y273993D01*
G01X1042776Y270993D02*
Y275993D01*
X1040433Y272410D01*
X1043599D01*
G01X1045216Y270993D02*
Y274326D01*
G01Y273410D02*
X1045406Y273826D01*
X1045723Y274160D01*
X1046166Y274326D01*
X1046609Y274160D01*
X1046926Y273826D01*
X1047116Y273410D01*
Y270993D01*
G01Y273410D02*
X1047306Y273826D01*
X1047623Y274160D01*
X1048066Y274326D01*
X1048509Y274160D01*
X1048826Y273826D01*
X1049016Y273326D01*
Y270993D01*
G01X1050316D02*
Y274326D01*
G01Y273410D02*
X1050506Y273826D01*
X1050823Y274160D01*
X1051266Y274326D01*
X1051709Y274160D01*
X1052026Y273826D01*
X1052216Y273410D01*
Y270993D01*
G01Y273410D02*
X1052406Y273826D01*
X1052723Y274160D01*
X1053166Y274326D01*
X1053609Y274160D01*
X1053926Y273826D01*
X1054116Y273326D01*
Y270993D01*
G01X1060959D02*
Y275993D01*
X1063873Y270993D01*
Y275993D01*
G01X1066249Y270993D02*
Y275993D01*
X1067769D01*
X1068276Y275743D01*
X1068656Y275160D01*
X1068783Y274493D01*
X1068656Y273826D01*
X1068339Y273326D01*
X1067769Y273076D01*
X1066249D01*
G01X1072616Y275993D02*
Y270993D01*
G01X1071159Y275993D02*
X1074073D01*
G01X1076386Y270993D02*
Y275993D01*
G01X1079046D02*
Y270993D01*
G01Y273493D02*
X1076386D01*
G01X943472Y60341D02*
X942972Y60721D01*
X942722Y61164D01*
X942639Y61671D01*
X942806Y62304D01*
X943222Y62747D01*
X943722Y62874D01*
X944222Y62811D01*
X944639Y62557D01*
X945472Y61291D01*
X946056Y60721D01*
X946889Y60341D01*
X947639Y60214D01*
Y62874D01*
G01X951123Y51702D02*
X950139Y57608D01*
X949154Y51702D01*
X951123D01*
G01X950139Y61544D02*
Y57608D01*
G01X964706D02*
X949745D01*
G01X949154Y71387D02*
X950139Y65482D01*
X951123Y71387D01*
X949154D01*
G01X950139Y61544D02*
Y65482D01*
G01X964706D02*
X949745D01*
G01X964558Y122797D02*
X968798Y125447D01*
X967547Y125561D01*
G01X964155Y123441D02*
X964961Y122152D01*
G01X951969Y138222D02*
X965432Y116680D01*
G01X955934Y133735D02*
X951969Y138222D01*
X954265Y132692D01*
X955934Y133735D01*
G01X968162Y128823D02*
X959152Y129088D01*
G01X966157Y128955D02*
G03I-2500J0D01*
G01X957518Y140776D02*
X987847Y147775D01*
G01X963051Y143063D02*
X957518Y140776D01*
X963494Y141145D01*
X963051Y143063D01*
G01X958848Y238922D02*
X995185Y246996D01*
G01X964400Y241163D02*
X958848Y238922D01*
X964827Y239242D01*
X964400Y241163D01*
G01X973367Y38907D02*
X979272Y39891D01*
X973367Y40875D01*
Y38907D01*
G01X985572Y39891D02*
X979272D01*
G01Y59182D02*
Y39497D01*
G01X980197Y149601D02*
X980698Y149118D01*
X981267Y148907D01*
X981841Y148954D01*
X982316Y149150D01*
X982716Y149669D01*
X982912Y150228D01*
X982861Y150729D01*
X982607Y151269D01*
X982081Y151575D01*
X981612Y151638D01*
X981056Y151510D01*
G01X981612Y151638D02*
X981926Y151967D01*
X982141Y152444D01*
X982152Y152960D01*
X981916Y153419D01*
X981514Y153754D01*
X980902Y153869D01*
X980365Y153660D01*
X979885Y153207D01*
G01X977256Y154311D02*
X974071Y145879D01*
G01X978164Y150095D02*
G03I-2501J0D01*
G01X984648Y253618D02*
X981394Y245212D01*
G01X985521Y249415D02*
G03I-2500J0D01*
G01X984179Y43391D02*
X984559Y42808D01*
X985065Y42474D01*
X985635Y42391D01*
X986142Y42474D01*
X986649Y42891D01*
X986965Y43391D01*
X987029Y43891D01*
X986902Y44474D01*
X986459Y44891D01*
X986015Y45058D01*
X985445D01*
G01X986015D02*
X986395Y45308D01*
X986712Y45724D01*
X986839Y46224D01*
X986712Y46724D01*
X986395Y47141D01*
X985825Y47391D01*
X985255Y47308D01*
X984685Y46974D01*
G01X996989Y40875D02*
X991084Y39891D01*
X996989Y38907D01*
Y40875D01*
G01X985572Y39891D02*
X991084D01*
G01Y59182D02*
Y39497D01*
G01X989870Y248376D02*
X988785Y253257D01*
X987275Y249251D01*
X990366Y249938D01*
G01X-1043962Y-705877D02*
Y2342823D01*
X2300638D01*
Y-705877D01*
X-1043962D01*
G01X-44244Y19685D02*
G03I-7874J0D01*
G01X-46213Y774410D02*
G03I-5905J0D01*
G01X-44244Y801969D02*
G03I-7874J0D01*
G01X37198Y-238524D02*
X37825Y-239049D01*
X38530Y-239364D01*
X39156D01*
X39783Y-239049D01*
X40253Y-238524D01*
X40488Y-237789D01*
X40331Y-237054D01*
X39940Y-236424D01*
X39235Y-236004D01*
X38295Y-235794D01*
X37746Y-235374D01*
X37511Y-234639D01*
X37668Y-233904D01*
X38060Y-233379D01*
X38608Y-233064D01*
X39156D01*
X39705Y-233274D01*
X40175Y-233799D01*
G01X43498Y-239364D02*
Y-233064D01*
G01X46788D02*
Y-239364D01*
G01Y-236214D02*
X43498D01*
G01X50503Y-233064D02*
X52383D01*
G01X51443D02*
Y-239364D01*
G01X50503D02*
X52383D01*
G01X59310D02*
X56176D01*
Y-233064D01*
X59310D01*
G01X58056Y-236109D02*
X56176D01*
G01X62241Y-239364D02*
Y-233064D01*
X65845Y-239364D01*
Y-233064D01*
G01X70186Y-240519D02*
X70500Y-239154D01*
G01X76643Y-233064D02*
Y-239364D01*
G01X74841Y-233064D02*
X78445D01*
G01X80985Y-239364D02*
X82943Y-233064D01*
X84901Y-239364D01*
G01X84196Y-237159D02*
X81690D01*
G01X88303Y-233064D02*
X90183D01*
G01X89243D02*
Y-239364D01*
G01X88303D02*
X90183D01*
G01X93193Y-233064D02*
X94290Y-239364D01*
X95543Y-233064D01*
X96796Y-239364D01*
X97893Y-233064D01*
G01X99885Y-239364D02*
X101843Y-233064D01*
X103801Y-239364D01*
G01X103096Y-237159D02*
X100590D01*
G01X106341Y-239364D02*
Y-233064D01*
X109945Y-239364D01*
Y-233064D01*
G01X119176Y-239364D02*
Y-233064D01*
X121135D01*
X121761Y-233379D01*
X122153Y-233799D01*
X122310Y-234639D01*
X122153Y-235479D01*
X121683Y-236004D01*
X121135Y-236319D01*
X119176D01*
G01X121135D02*
X122310Y-239364D01*
G01X127043Y-239574D02*
X126886Y-239469D01*
Y-239259D01*
X127043Y-239154D01*
X127200Y-239259D01*
Y-239469D01*
X127043Y-239574D01*
G01X133343Y-239364D02*
X132716Y-239259D01*
X132168Y-238839D01*
X131698Y-238209D01*
X131385Y-237474D01*
X131228Y-236634D01*
Y-235794D01*
X131385Y-234954D01*
X131698Y-234219D01*
X132168Y-233589D01*
X132716Y-233169D01*
X133343Y-233064D01*
X133970Y-233169D01*
X134518Y-233589D01*
X134988Y-234219D01*
X135301Y-234954D01*
X135458Y-235794D01*
Y-236634D01*
X135301Y-237474D01*
X134988Y-238209D01*
X134518Y-238839D01*
X133970Y-239259D01*
X133343Y-239364D01*
G01X139643Y-239574D02*
X139486Y-239469D01*
Y-239259D01*
X139643Y-239154D01*
X139800Y-239259D01*
Y-239469D01*
X139643Y-239574D01*
G01X147666Y-233589D02*
X147196Y-233274D01*
X146648Y-233064D01*
X146021D01*
X145316Y-233379D01*
X144768Y-233904D01*
X144376Y-234534D01*
X144063Y-235584D01*
X143985Y-236529D01*
X144141Y-237474D01*
X144376Y-238104D01*
X144846Y-238734D01*
X145395Y-239154D01*
X145943Y-239364D01*
X146491D01*
X147040Y-239154D01*
X147510Y-238839D01*
X147901Y-238419D01*
G01X152243Y-239574D02*
X152086Y-239469D01*
Y-239259D01*
X152243Y-239154D01*
X152400Y-239259D01*
Y-239469D01*
X152243Y-239574D01*
G01X37120Y-229364D02*
Y-223064D01*
G01X40096D02*
X37120Y-226949D01*
G01X40566Y-229364D02*
X38451Y-225164D01*
G01X43420Y-223064D02*
Y-227579D01*
X43733Y-228524D01*
X44360Y-229154D01*
X45143Y-229364D01*
X45926Y-229154D01*
X46553Y-228524D01*
X46866Y-227579D01*
Y-223064D01*
G01X53010Y-229364D02*
X49876D01*
Y-223064D01*
X53010D01*
G01X51756Y-226109D02*
X49876D01*
G01X56803Y-223064D02*
X58683D01*
G01X57743D02*
Y-229364D01*
G01X56803D02*
X58683D01*
G01X68698Y-228524D02*
X69325Y-229049D01*
X70030Y-229364D01*
X70656D01*
X71283Y-229049D01*
X71753Y-228524D01*
X71988Y-227789D01*
X71831Y-227054D01*
X71440Y-226424D01*
X70735Y-226004D01*
X69795Y-225794D01*
X69246Y-225374D01*
X69011Y-224639D01*
X69168Y-223904D01*
X69560Y-223379D01*
X70108Y-223064D01*
X70656D01*
X71205Y-223274D01*
X71675Y-223799D01*
G01X74998Y-229364D02*
Y-223064D01*
G01X78288D02*
Y-229364D01*
G01Y-226214D02*
X74998D01*
G01X80985Y-229364D02*
X82943Y-223064D01*
X84901Y-229364D01*
G01X84196Y-227159D02*
X81690D01*
G01X87441Y-229364D02*
Y-223064D01*
X91045Y-229364D01*
Y-223064D01*
G01X100198Y-229364D02*
Y-223064D01*
G01X103488D02*
Y-229364D01*
G01Y-226214D02*
X100198D01*
G01X106498Y-228524D02*
X107125Y-229049D01*
X107830Y-229364D01*
X108456D01*
X109083Y-229049D01*
X109553Y-228524D01*
X109788Y-227789D01*
X109631Y-227054D01*
X109240Y-226424D01*
X108535Y-226004D01*
X107595Y-225794D01*
X107046Y-225374D01*
X106811Y-224639D01*
X106968Y-223904D01*
X107360Y-223379D01*
X107908Y-223064D01*
X108456D01*
X109005Y-223274D01*
X109475Y-223799D01*
G01X113503Y-223064D02*
X115383D01*
G01X114443D02*
Y-229364D01*
G01X113503D02*
X115383D01*
G01X118785D02*
X120743Y-223064D01*
X122701Y-229364D01*
G01X121996Y-227159D02*
X119490D01*
G01X125241Y-229364D02*
Y-223064D01*
X128845Y-229364D01*
Y-223064D01*
G01X133813Y-226214D02*
X135380D01*
Y-228104D01*
X134910Y-228734D01*
X134361Y-229154D01*
X133578Y-229364D01*
X132795Y-229154D01*
X132246Y-228734D01*
X131776Y-228104D01*
X131463Y-227369D01*
X131306Y-226529D01*
Y-225794D01*
X131463Y-225164D01*
X131776Y-224429D01*
X132246Y-223799D01*
X132716Y-223379D01*
X133343Y-223064D01*
X133891D01*
X134518Y-223274D01*
X134988Y-223694D01*
G01X139486Y-230519D02*
X139800Y-229154D01*
G01X145943Y-223064D02*
Y-229364D01*
G01X144141Y-223064D02*
X147745D01*
G01X150285Y-229364D02*
X152243Y-223064D01*
X154201Y-229364D01*
G01X153496Y-227159D02*
X150990D01*
G01X158543Y-229364D02*
X157916Y-229259D01*
X157368Y-228839D01*
X156898Y-228209D01*
X156585Y-227474D01*
X156428Y-226634D01*
Y-225794D01*
X156585Y-224954D01*
X156898Y-224219D01*
X157368Y-223589D01*
X157916Y-223169D01*
X158543Y-223064D01*
X159170Y-223169D01*
X159718Y-223589D01*
X160188Y-224219D01*
X160501Y-224954D01*
X160658Y-225794D01*
Y-226634D01*
X160501Y-227474D01*
X160188Y-228209D01*
X159718Y-228839D01*
X159170Y-229259D01*
X158543Y-229364D01*
G01X171143D02*
Y-226529D01*
X169576Y-223064D01*
G01X172710D02*
X171143Y-226529D01*
G01X175720Y-223064D02*
Y-227579D01*
X176033Y-228524D01*
X176660Y-229154D01*
X177443Y-229364D01*
X178226Y-229154D01*
X178853Y-228524D01*
X179166Y-227579D01*
Y-223064D01*
G01X181785Y-229364D02*
X183743Y-223064D01*
X185701Y-229364D01*
G01X184996Y-227159D02*
X182490D01*
G01X188241Y-229364D02*
Y-223064D01*
X191845Y-229364D01*
Y-223064D01*
G01X37041Y-219364D02*
Y-213064D01*
X40645Y-219364D01*
Y-213064D01*
G01X45143Y-219364D02*
X44516Y-219259D01*
X43968Y-218839D01*
X43498Y-218209D01*
X43185Y-217474D01*
X43028Y-216634D01*
Y-215794D01*
X43185Y-214954D01*
X43498Y-214219D01*
X43968Y-213589D01*
X44516Y-213169D01*
X45143Y-213064D01*
X45770Y-213169D01*
X46318Y-213589D01*
X46788Y-214219D01*
X47101Y-214954D01*
X47258Y-215794D01*
Y-216634D01*
X47101Y-217474D01*
X46788Y-218209D01*
X46318Y-218839D01*
X45770Y-219259D01*
X45143Y-219364D01*
G01X51443Y-219574D02*
X51286Y-219469D01*
Y-219259D01*
X51443Y-219154D01*
X51600Y-219259D01*
Y-219469D01*
X51443Y-219574D01*
G01X57743Y-219364D02*
Y-213064D01*
X56803Y-214324D01*
G01Y-219364D02*
X58683D01*
G01X64043D02*
X64591Y-219259D01*
X65218Y-218944D01*
X65610Y-218419D01*
X65766Y-217684D01*
X65610Y-216949D01*
X65140Y-216319D01*
X64435Y-216004D01*
X63651D01*
X63181Y-215794D01*
X62790Y-215269D01*
X62633Y-214534D01*
X62868Y-213799D01*
X63416Y-213274D01*
X64043Y-213064D01*
X64670Y-213274D01*
X65218Y-213799D01*
X65453Y-214534D01*
X65296Y-215269D01*
X64905Y-215794D01*
X64435Y-216004D01*
X63651D01*
X62946Y-216319D01*
X62476Y-216949D01*
X62320Y-217684D01*
X62476Y-218419D01*
X62868Y-218944D01*
X63495Y-219259D01*
X64043Y-219364D01*
G01X70343D02*
X70891Y-219259D01*
X71518Y-218944D01*
X71910Y-218419D01*
X72066Y-217684D01*
X71910Y-216949D01*
X71440Y-216319D01*
X70735Y-216004D01*
X69951D01*
X69481Y-215794D01*
X69090Y-215269D01*
X68933Y-214534D01*
X69168Y-213799D01*
X69716Y-213274D01*
X70343Y-213064D01*
X70970Y-213274D01*
X71518Y-213799D01*
X71753Y-214534D01*
X71596Y-215269D01*
X71205Y-215794D01*
X70735Y-216004D01*
X69951D01*
X69246Y-216319D01*
X68776Y-216949D01*
X68620Y-217684D01*
X68776Y-218419D01*
X69168Y-218944D01*
X69795Y-219259D01*
X70343Y-219364D01*
G01X76486Y-220519D02*
X76800Y-219154D01*
G01X80593Y-213064D02*
X81690Y-219364D01*
X82943Y-213064D01*
X84196Y-219364D01*
X85293Y-213064D01*
G01X90810Y-219364D02*
X87676D01*
Y-213064D01*
X90810D01*
G01X89556Y-216109D02*
X87676D01*
G01X93741Y-219364D02*
Y-213064D01*
X97345Y-219364D01*
Y-213064D01*
G01X106498Y-219364D02*
Y-213064D01*
G01X109788D02*
Y-219364D01*
G01Y-216214D02*
X106498D01*
G01X112093Y-213064D02*
X113190Y-219364D01*
X114443Y-213064D01*
X115696Y-219364D01*
X116793Y-213064D01*
G01X118785Y-219364D02*
X120743Y-213064D01*
X122701Y-219364D01*
G01X121996Y-217159D02*
X119490D01*
G01X131855Y-214114D02*
X132325Y-213484D01*
X132873Y-213169D01*
X133500Y-213064D01*
X134283Y-213274D01*
X134831Y-213799D01*
X134988Y-214429D01*
X134910Y-215059D01*
X134596Y-215584D01*
X133030Y-216634D01*
X132325Y-217369D01*
X131855Y-218419D01*
X131698Y-219364D01*
X134988D01*
G01X137841D02*
Y-213064D01*
X141445Y-219364D01*
Y-213064D01*
G01X144220Y-219364D02*
Y-213064D01*
X145786D01*
X146413Y-213379D01*
X146883Y-213799D01*
X147275Y-214429D01*
X147588Y-215164D01*
X147666Y-216214D01*
X147588Y-217264D01*
X147275Y-217999D01*
X146883Y-218629D01*
X146413Y-219049D01*
X145786Y-219364D01*
X144220D01*
G01X156976D02*
Y-213064D01*
X158935D01*
X159561Y-213379D01*
X159953Y-213799D01*
X160110Y-214639D01*
X159953Y-215479D01*
X159483Y-216004D01*
X158935Y-216319D01*
X156976D01*
G01X158935D02*
X160110Y-219364D01*
G01X163120D02*
Y-213064D01*
X164686D01*
X165313Y-213379D01*
X165783Y-213799D01*
X166175Y-214429D01*
X166488Y-215164D01*
X166566Y-216214D01*
X166488Y-217264D01*
X166175Y-217999D01*
X165783Y-218629D01*
X165313Y-219049D01*
X164686Y-219364D01*
X163120D01*
G01X171143Y-219574D02*
X170986Y-219469D01*
Y-219259D01*
X171143Y-219154D01*
X171300Y-219259D01*
Y-219469D01*
X171143Y-219574D01*
G01X61143Y-206664D02*
X58623Y-206247D01*
X56418Y-204581D01*
X54528Y-202081D01*
X53268Y-199164D01*
X52638Y-195831D01*
Y-192497D01*
X53268Y-189164D01*
X54528Y-186247D01*
X56418Y-183748D01*
X58623Y-182081D01*
X61143Y-181664D01*
X63663Y-182081D01*
X65868Y-183748D01*
X67758Y-186247D01*
X69018Y-189164D01*
X69648Y-192497D01*
Y-195831D01*
X69018Y-199164D01*
X67758Y-202081D01*
X65868Y-204581D01*
X63663Y-206247D01*
X61143Y-206664D01*
G01X63663Y-199997D02*
X67443Y-206664D01*
G01X80988Y-189998D02*
Y-201664D01*
X82248Y-204581D01*
X84138Y-206247D01*
X86343Y-206664D01*
X88548Y-206247D01*
X90438Y-204581D01*
X91698Y-201664D01*
G01Y-206664D02*
Y-189998D01*
G01X117213Y-206664D02*
Y-189998D01*
G01Y-192914D02*
X115953Y-191248D01*
X114063Y-190414D01*
X111858Y-189998D01*
X109653Y-190831D01*
X107763Y-192497D01*
X106503Y-194998D01*
X105873Y-198331D01*
X106503Y-201664D01*
X107763Y-204165D01*
X109653Y-205831D01*
X111858Y-206664D01*
X114063Y-206247D01*
X115953Y-204998D01*
X117213Y-203331D01*
G01X131388Y-206664D02*
Y-189998D01*
G01Y-194164D02*
X132648Y-192081D01*
X134538Y-190414D01*
X137058Y-189998D01*
X139263Y-190414D01*
X141153Y-192081D01*
X142098Y-194998D01*
Y-206664D01*
G01X161943Y-181664D02*
Y-206664D01*
G01X157533Y-189998D02*
X166353D01*
G01X192813Y-206664D02*
Y-189998D01*
G01Y-192914D02*
X191553Y-191248D01*
X189663Y-190414D01*
X187458Y-189998D01*
X185253Y-190831D01*
X183363Y-192497D01*
X182103Y-194998D01*
X181473Y-198331D01*
X182103Y-201664D01*
X183363Y-204165D01*
X185253Y-205831D01*
X187458Y-206664D01*
X189663Y-206247D01*
X191553Y-204998D01*
X192813Y-203331D01*
G01X232493Y-186364D02*
Y-194364D01*
X236493D01*
G01X244293D02*
Y-189031D01*
G01Y-189964D02*
X243893Y-189431D01*
X243293Y-189164D01*
X242593Y-189031D01*
X241893Y-189297D01*
X241293Y-189831D01*
X240893Y-190631D01*
X240693Y-191697D01*
X240893Y-192764D01*
X241293Y-193564D01*
X241893Y-194097D01*
X242593Y-194364D01*
X243293Y-194231D01*
X243893Y-193831D01*
X244293Y-193298D01*
G01X248393Y-196764D02*
X248993Y-197031D01*
X249793Y-196764D01*
X250293Y-196231D01*
X250693Y-195564D01*
X251293Y-193431D01*
X252593Y-189031D01*
G01X249393D02*
X251293Y-193431D01*
G01X256993Y-190764D02*
X260193D01*
X259893Y-189831D01*
X259393Y-189297D01*
X258693Y-189031D01*
X257993Y-189164D01*
X257393Y-189564D01*
X256993Y-190497D01*
X256793Y-191298D01*
Y-192097D01*
X256993Y-192897D01*
X257493Y-193697D01*
X258093Y-194231D01*
X258793Y-194364D01*
X259493Y-194097D01*
X260193Y-193298D01*
G01X265093Y-194364D02*
Y-189031D01*
G01Y-190097D02*
X265593Y-189564D01*
X266093Y-189164D01*
X266793Y-189031D01*
X267293Y-189164D01*
X267893Y-189564D01*
G01X254793Y-236364D02*
X257193D01*
G01X255993D02*
Y-244364D01*
G01X254793D02*
X257193D01*
G01X262593D02*
Y-239031D01*
G01Y-240097D02*
X263093Y-239564D01*
X263593Y-239164D01*
X264293Y-239031D01*
X264793Y-239164D01*
X265393Y-239564D01*
G01X270493Y-240764D02*
X273693D01*
X273393Y-239831D01*
X272893Y-239297D01*
X272193Y-239031D01*
X271493Y-239164D01*
X270893Y-239564D01*
X270493Y-240497D01*
X270293Y-241298D01*
Y-242097D01*
X270493Y-242897D01*
X270993Y-243697D01*
X271593Y-244231D01*
X272293Y-244364D01*
X272993Y-244097D01*
X273693Y-243298D01*
G01X278293Y-244364D02*
Y-239031D01*
G01Y-240364D02*
X278693Y-239697D01*
X279293Y-239164D01*
X280093Y-239031D01*
X280793Y-239164D01*
X281393Y-239697D01*
X281693Y-240631D01*
Y-244364D01*
G01X286493Y-240764D02*
X289693D01*
X289393Y-239831D01*
X288893Y-239297D01*
X288193Y-239031D01*
X287493Y-239164D01*
X286893Y-239564D01*
X286493Y-240497D01*
X286293Y-241298D01*
Y-242097D01*
X286493Y-242897D01*
X286993Y-243697D01*
X287593Y-244231D01*
X288293Y-244364D01*
X288993Y-244097D01*
X289693Y-243298D01*
G01X251493Y-219364D02*
Y-211364D01*
X253893D01*
X254693Y-211764D01*
X255293Y-212697D01*
X255493Y-213764D01*
X255293Y-214831D01*
X254793Y-215631D01*
X253893Y-216031D01*
X251493D01*
G01X258993Y-219364D02*
X261493Y-211364D01*
X263993Y-219364D01*
G01X263093Y-216564D02*
X259893D01*
G01X267193Y-219364D02*
Y-211364D01*
X271793Y-219364D01*
Y-211364D01*
G01X279493Y-219364D02*
X275493D01*
Y-211364D01*
X279493D01*
G01X277893Y-215231D02*
X275493D01*
G01X283493Y-211364D02*
Y-219364D01*
X287493D01*
G01X359093Y-237697D02*
X359693Y-236897D01*
X360393Y-236497D01*
X361193Y-236364D01*
X362193Y-236631D01*
X362893Y-237297D01*
X363093Y-238097D01*
X362993Y-238898D01*
X362593Y-239564D01*
X360593Y-240897D01*
X359693Y-241831D01*
X359093Y-243164D01*
X358893Y-244364D01*
X363093D01*
G01X368993Y-236364D02*
X368193Y-236631D01*
X367593Y-237297D01*
X367193Y-238097D01*
X366893Y-239164D01*
X366793Y-240364D01*
X366893Y-241564D01*
X367193Y-242631D01*
X367593Y-243431D01*
X368193Y-244097D01*
X368993Y-244364D01*
X369793Y-244097D01*
X370393Y-243431D01*
X370793Y-242631D01*
X371093Y-241564D01*
X371193Y-240364D01*
X371093Y-239164D01*
X370793Y-238097D01*
X370393Y-237297D01*
X369793Y-236631D01*
X368993Y-236364D01*
G01X376993Y-244364D02*
Y-236364D01*
X375793Y-237964D01*
G01Y-244364D02*
X378193D01*
G01X383093Y-237697D02*
X383693Y-236897D01*
X384393Y-236497D01*
X385193Y-236364D01*
X386193Y-236631D01*
X386893Y-237297D01*
X387093Y-238097D01*
X386993Y-238898D01*
X386593Y-239564D01*
X384593Y-240897D01*
X383693Y-241831D01*
X383093Y-243164D01*
X382893Y-244364D01*
X387093D01*
G01X391193Y-244631D02*
X394793Y-236364D01*
G01X400993Y-244364D02*
Y-236364D01*
X399793Y-237964D01*
G01Y-244364D02*
X402193D01*
G01X408993Y-236364D02*
X408193Y-236631D01*
X407593Y-237297D01*
X407193Y-238097D01*
X406893Y-239164D01*
X406793Y-240364D01*
X406893Y-241564D01*
X407193Y-242631D01*
X407593Y-243431D01*
X408193Y-244097D01*
X408993Y-244364D01*
X409793Y-244097D01*
X410393Y-243431D01*
X410793Y-242631D01*
X411093Y-241564D01*
X411193Y-240364D01*
X411093Y-239164D01*
X410793Y-238097D01*
X410393Y-237297D01*
X409793Y-236631D01*
X408993Y-236364D01*
G01X415193Y-244631D02*
X418793Y-236364D01*
G01X422793Y-242764D02*
X423393Y-243697D01*
X424193Y-244231D01*
X425093Y-244364D01*
X425893Y-244231D01*
X426693Y-243564D01*
X427193Y-242764D01*
X427293Y-241964D01*
X427093Y-241031D01*
X426393Y-240364D01*
X425693Y-240097D01*
X424793D01*
G01X425693D02*
X426293Y-239697D01*
X426793Y-239031D01*
X426993Y-238231D01*
X426793Y-237431D01*
X426293Y-236764D01*
X425393Y-236364D01*
X424493Y-236497D01*
X423593Y-237031D01*
G01X432993Y-244364D02*
Y-236364D01*
X431793Y-237964D01*
G01Y-244364D02*
X434193D01*
G01X358793Y-219364D02*
Y-211364D01*
X360793D01*
X361593Y-211764D01*
X362193Y-212297D01*
X362693Y-213097D01*
X363093Y-214031D01*
X363193Y-215364D01*
X363093Y-216697D01*
X362693Y-217631D01*
X362193Y-218431D01*
X361593Y-218964D01*
X360793Y-219364D01*
X358793D01*
G01X366493D02*
X368993Y-211364D01*
X371493Y-219364D01*
G01X370593Y-216564D02*
X367393D01*
G01X376993Y-211364D02*
Y-219364D01*
G01X374693Y-211364D02*
X379293D01*
G01X383093Y-216031D02*
X383793Y-215097D01*
X384393Y-214564D01*
X385193Y-214297D01*
X385893Y-214564D01*
X386393Y-215097D01*
X386793Y-215897D01*
X386893Y-216831D01*
X386793Y-217631D01*
X386393Y-218431D01*
X385793Y-219097D01*
X385093Y-219364D01*
X384293Y-219097D01*
X383593Y-218298D01*
X383193Y-217097D01*
X383093Y-215764D01*
X383293Y-214031D01*
X383593Y-213097D01*
X384093Y-212164D01*
X384793Y-211497D01*
X385493Y-211364D01*
X386193Y-211631D01*
X386693Y-212297D01*
G01X390393Y-219364D02*
Y-211364D01*
X392993Y-218031D01*
X395593Y-211364D01*
Y-219364D01*
G01X400993Y-211364D02*
Y-219364D01*
G01X398693Y-211364D02*
X403293D01*
G01X406893Y-219364D02*
Y-211364D01*
G01X411093D02*
Y-219364D01*
G01Y-215364D02*
X406893D01*
G01X414793Y-217764D02*
X415393Y-218697D01*
X416193Y-219231D01*
X417093Y-219364D01*
X417893Y-219231D01*
X418693Y-218564D01*
X419193Y-217764D01*
X419293Y-216964D01*
X419093Y-216031D01*
X418393Y-215364D01*
X417693Y-215097D01*
X416793D01*
G01X417693D02*
X418293Y-214697D01*
X418793Y-214031D01*
X418993Y-213231D01*
X418793Y-212431D01*
X418293Y-211764D01*
X417393Y-211364D01*
X416493Y-211497D01*
X415593Y-212031D01*
G01X422493Y-219364D02*
X424993Y-211364D01*
X427493Y-219364D01*
G01X426593Y-216564D02*
X423393D01*
G01X430793Y-219364D02*
Y-211364D01*
X432793D01*
X433593Y-211764D01*
X434193Y-212297D01*
X434693Y-213097D01*
X435093Y-214031D01*
X435193Y-215364D01*
X435093Y-216697D01*
X434693Y-217631D01*
X434193Y-218431D01*
X433593Y-218964D01*
X432793Y-219364D01*
X430793D01*
G01X440993Y-211364D02*
X440193Y-211631D01*
X439593Y-212297D01*
X439193Y-213097D01*
X438893Y-214164D01*
X438793Y-215364D01*
X438893Y-216564D01*
X439193Y-217631D01*
X439593Y-218431D01*
X440193Y-219097D01*
X440993Y-219364D01*
X441793Y-219097D01*
X442393Y-218431D01*
X442793Y-217631D01*
X443093Y-216564D01*
X443193Y-215364D01*
X443093Y-214164D01*
X442793Y-213097D01*
X442393Y-212297D01*
X441793Y-211631D01*
X440993Y-211364D01*
G01X380993Y-186364D02*
Y-194364D01*
G01X378693Y-186364D02*
X383293D01*
G01X387093Y-191031D02*
X387793Y-190097D01*
X388393Y-189564D01*
X389193Y-189297D01*
X389893Y-189564D01*
X390393Y-190097D01*
X390793Y-190897D01*
X390893Y-191831D01*
X390793Y-192631D01*
X390393Y-193431D01*
X389793Y-194097D01*
X389093Y-194364D01*
X388293Y-194097D01*
X387593Y-193298D01*
X387193Y-192097D01*
X387093Y-190764D01*
X387293Y-189031D01*
X387593Y-188097D01*
X388093Y-187164D01*
X388793Y-186497D01*
X389493Y-186364D01*
X390193Y-186631D01*
X390693Y-187297D01*
G01X394393Y-194364D02*
Y-186364D01*
X396993Y-193031D01*
X399593Y-186364D01*
Y-194364D01*
G01X401993Y-197031D02*
X407993D01*
G01X415193Y-187031D02*
X414593Y-186631D01*
X413893Y-186364D01*
X413093D01*
X412193Y-186764D01*
X411493Y-187431D01*
X410993Y-188231D01*
X410593Y-189564D01*
X410493Y-190764D01*
X410693Y-191964D01*
X410993Y-192764D01*
X411593Y-193564D01*
X412293Y-194097D01*
X412993Y-194364D01*
X413693D01*
X414393Y-194097D01*
X414993Y-193697D01*
X415493Y-193164D01*
G01X418393Y-194364D02*
Y-186364D01*
X420993Y-193031D01*
X423593Y-186364D01*
Y-194364D01*
G01X425993Y-197031D02*
X431993D01*
G01X434793Y-194364D02*
Y-186364D01*
X436793D01*
X437593Y-186764D01*
X438193Y-187297D01*
X438693Y-188097D01*
X439093Y-189031D01*
X439193Y-190364D01*
X439093Y-191697D01*
X438693Y-192631D01*
X438193Y-193431D01*
X437593Y-193964D01*
X436793Y-194364D01*
X434793D01*
G01X393336Y890789D02*
X393884Y890894D01*
X394511Y891209D01*
X394903Y891734D01*
X395059Y892469D01*
X394903Y893204D01*
X394433Y893834D01*
X393728Y894149D01*
X392944D01*
X392474Y894359D01*
X392083Y894884D01*
X391926Y895619D01*
X392161Y896354D01*
X392709Y896879D01*
X393336Y897089D01*
X393963Y896879D01*
X394511Y896354D01*
X394746Y895619D01*
X394589Y894884D01*
X394198Y894359D01*
X393728Y894149D01*
X392944D01*
X392239Y893834D01*
X391769Y893204D01*
X391613Y892469D01*
X391769Y891734D01*
X392161Y891209D01*
X392788Y890894D01*
X393336Y890789D01*
G01X398304Y891524D02*
X398853Y890999D01*
X399479Y890789D01*
X400106Y890999D01*
X400654Y891629D01*
X401046Y892574D01*
X401203Y893519D01*
Y894674D01*
X401046Y895619D01*
X400654Y896459D01*
X400184Y896879D01*
X399636Y897089D01*
X399009Y896879D01*
X398539Y896459D01*
X398226Y895829D01*
X398069Y894989D01*
X398226Y894254D01*
X398618Y893519D01*
X399088Y893099D01*
X399636Y892994D01*
X400263Y893204D01*
X400733Y893729D01*
X401203Y894674D01*
G01X405936Y890789D02*
X406484Y890894D01*
X407111Y891209D01*
X407503Y891734D01*
X407659Y892469D01*
X407503Y893204D01*
X407033Y893834D01*
X406328Y894149D01*
X405544D01*
X405074Y894359D01*
X404683Y894884D01*
X404526Y895619D01*
X404761Y896354D01*
X405309Y896879D01*
X405936Y897089D01*
X406563Y896879D01*
X407111Y896354D01*
X407346Y895619D01*
X407189Y894884D01*
X406798Y894359D01*
X406328Y894149D01*
X405544D01*
X404839Y893834D01*
X404369Y893204D01*
X404213Y892469D01*
X404369Y891734D01*
X404761Y891209D01*
X405388Y890894D01*
X405936Y890789D01*
G01X410513Y891734D02*
X410983Y891209D01*
X411531Y890894D01*
X412236Y890789D01*
X412941Y890999D01*
X413489Y891419D01*
X413881Y892154D01*
X413959Y892994D01*
X413803Y893834D01*
X413411Y894359D01*
X412863Y894779D01*
X412314Y894884D01*
X411766Y894779D01*
X411061Y894359D01*
X411296Y897089D01*
X413411D01*
G01X418536Y890579D02*
X418379Y890684D01*
Y890894D01*
X418536Y890999D01*
X418693Y890894D01*
Y890684D01*
X418536Y890579D01*
G01X424679Y890789D02*
X424836Y892154D01*
X425071Y893309D01*
X425384Y894359D01*
X425776Y895514D01*
X426403Y897089D01*
X423269D01*
G01X429413Y891734D02*
X429883Y891209D01*
X430431Y890894D01*
X431136Y890789D01*
X431841Y890999D01*
X432389Y891419D01*
X432781Y892154D01*
X432859Y892994D01*
X432703Y893834D01*
X432311Y894359D01*
X431763Y894779D01*
X431214Y894884D01*
X430666Y894779D01*
X429961Y894359D01*
X430196Y897089D01*
X432311D01*
G01X473793Y-244364D02*
Y-236364D01*
X475793D01*
X476593Y-236764D01*
X477193Y-237297D01*
X477693Y-238097D01*
X478093Y-239031D01*
X478193Y-240364D01*
X478093Y-241697D01*
X477693Y-242631D01*
X477193Y-243431D01*
X476593Y-243964D01*
X475793Y-244364D01*
X473793D01*
G01X503493D02*
Y-236364D01*
X502293Y-237964D01*
G01Y-244364D02*
X504693D01*
G01X509593Y-241031D02*
X510293Y-240097D01*
X510893Y-239564D01*
X511693Y-239297D01*
X512393Y-239564D01*
X512893Y-240097D01*
X513293Y-240897D01*
X513393Y-241831D01*
X513293Y-242631D01*
X512893Y-243431D01*
X512293Y-244097D01*
X511593Y-244364D01*
X510793Y-244097D01*
X510093Y-243298D01*
X509693Y-242097D01*
X509593Y-240764D01*
X509793Y-239031D01*
X510093Y-238097D01*
X510593Y-237164D01*
X511293Y-236497D01*
X511993Y-236364D01*
X512693Y-236631D01*
X513193Y-237297D01*
G01X814961Y19685D02*
G03I-7874J0D01*
G01X812992Y47244D02*
G03I-5905J0D01*
G01X814961Y801969D02*
G03I-7874J0D01*
G01X889135Y346411D02*
X889030Y346959D01*
X888715Y347586D01*
X888190Y347978D01*
X887455Y348134D01*
X886720Y347978D01*
X886090Y347508D01*
X885775Y346803D01*
Y346019D01*
X885565Y345549D01*
X885040Y345158D01*
X884305Y345001D01*
X883570Y345236D01*
X883045Y345784D01*
X882835Y346411D01*
X883045Y347038D01*
X883570Y347586D01*
X884305Y347821D01*
X885040Y347664D01*
X885565Y347273D01*
X885775Y346803D01*
Y346019D01*
X886090Y345314D01*
X886720Y344844D01*
X887455Y344688D01*
X888190Y344844D01*
X888715Y345236D01*
X889030Y345863D01*
X889135Y346411D01*
G01X883885Y351223D02*
X883255Y351693D01*
X882940Y352241D01*
X882835Y352868D01*
X883045Y353651D01*
X883570Y354199D01*
X884200Y354356D01*
X884830Y354278D01*
X885355Y353964D01*
X886405Y352398D01*
X887140Y351693D01*
X888190Y351223D01*
X889135Y351066D01*
Y354356D01*
G01Y359011D02*
X882835D01*
X884095Y358071D01*
G01X889135D02*
Y359951D01*
G01X886510Y363823D02*
X885775Y364371D01*
X885355Y364841D01*
X885145Y365468D01*
X885355Y366016D01*
X885775Y366408D01*
X886405Y366721D01*
X887140Y366799D01*
X887770Y366721D01*
X888400Y366408D01*
X888925Y365938D01*
X889135Y365389D01*
X888925Y364763D01*
X888295Y364214D01*
X887350Y363901D01*
X886300Y363823D01*
X884935Y363979D01*
X884200Y364214D01*
X883465Y364606D01*
X882940Y365154D01*
X882835Y365703D01*
X883045Y366251D01*
X883570Y366643D01*
G01X889345Y371611D02*
X889240Y371454D01*
X889030D01*
X888925Y371611D01*
X889030Y371768D01*
X889240D01*
X889345Y371611D01*
G01X888190Y376188D02*
X888715Y376658D01*
X889030Y377206D01*
X889135Y377911D01*
X888925Y378616D01*
X888505Y379164D01*
X887770Y379556D01*
X886930Y379634D01*
X886090Y379478D01*
X885565Y379086D01*
X885145Y378538D01*
X885040Y377989D01*
X885145Y377441D01*
X885565Y376736D01*
X882835Y376971D01*
Y379086D01*
G01X889135Y385151D02*
X882835D01*
X887350Y382253D01*
Y386169D01*
G01X910375Y287135D02*
X1154784D01*
Y3119D01*
X910375D01*
Y287135D01*
G01X957619Y138710D02*
G03I-5906J0D01*
G01X959036Y237213D02*
G03I-7874J0D01*
G01X965887Y65482D02*
X975335D01*
G02Y57608I0J-3937D01*
G01X965887D01*
G01X995020Y65482D02*
G03Y57608I0J-3937D01*
G01X1004469D01*
G01X995020Y65482D02*
X1004469D01*
M02*
